FILE_TYPE = MACRO_DRAWING;
SET COLOR_WIRE YELLOW;
SET COLOR_PROP ORANGE;
SET COLOR_DOT WHITE;
SET COLOR_ARC YELLOW;
SET COLOR_BODY GREEN;
SET COLOR_NOTE PURPLE;
SET PROP_DISPLAY VALUE;
SET PAGE_NUMBER P16;
SET PATH_NUMBER P193;
FORCEADD Q_CAP..1
(-425 4425);
FORCEPROP 1 LAST PACK_TYPE 0402
J 0
(-375 4250);
DISPLAY 0.510638 (-375 4250);
PAINT SKYBLUE (-375 4250);
FORCEPROP 1 LAST VALUE 0.1UF
J 0
(-375 4450);
DISPLAY 0.510638 (-375 4450);
PAINT SKYBLUE (-375 4450);
FORCEPROP 1 LAST TOLERANCE 10%
J 0
(-375 4350);
DISPLAY 0.510638 (-375 4350);
PAINT SKYBLUE (-375 4350);
FORCEPROP 1 LAST MATERIAL X7R
J 0
(-375 4300);
DISPLAY 0.510638 (-375 4300);
PAINT SKYBLUE (-375 4300);
FORCEPROP 1 LAST VOLTAGE 25V
J 0
(-375 4400);
DISPLAY 0.510638 (-375 4400);
PAINT SKYBLUE (-375 4400);
FORCEPROP 1 LAST PART_NUMBER CH4104K1B00
J 0
(-375 4200);
DISPLAY 0.510638 (-375 4200);
PAINT WHITE (-375 4200);
FORCEPROP 1 LAST PATH I100
J 0
(-375 4575);
DISPLAY 0.978723 (-375 4575);
PAINT WHITE (-375 4575);
DISPLAY INVISIBLE (-375 4575);
FORCEPROP 2 LAST CDS_LIB pure_quanta
J 0
(-425 4425);
DISPLAY INVISIBLE (-425 4425);
FORCEPROP 1 LAST LOCATION C77
J 0
(-375 4500);
DISPLAY 0.702128 (-375 4500);
PAINT YELLOW (-375 4500);
FORCEPROP 1 LASTPIN (-425 4525) $PN 1
J 0
(-415 4505);
DISPLAY 0.808511 (-415 4505);
PAINT WHITE (-415 4505);
FORCEPROP 1 LASTPIN (-425 4325) $PN 2
J 0
(-415 4305);
DISPLAY 0.808511 (-415 4305);
PAINT WHITE (-415 4305);
FORCEPROP 2 LAST $SEC 1
J 0
(-375 4625);
DISPLAY 0.680851 (-375 4625);
PAINT MONO (-375 4625);
DISPLAY INVISIBLE (-375 4625);
FORCEPROP 0 LAST CDS_SEC 1
J 0
(-375 4625);
DISPLAY 0.680851 (-375 4625);
PAINT MONO (-375 4625);
DISPLAY INVISIBLE (-375 4625);
FORCEADD UNIVERSAL_GND..1
(2625 -250);
FORCEPROP 3 LASTPIN (2625 -200) SIG_NAME GND\g
J 0
(2635 -190);
DISPLAY 0.659574 (2635 -190);
PAINT MONO (2635 -190);
DISPLAY INVISIBLE (2635 -190);
FORCEPROP 1 LAST PATH I105
J 0
(2700 -250);
DISPLAY 0.872340 (2700 -250);
PAINT AQUA (2700 -250);
DISPLAY INVISIBLE (2700 -250);
FORCEPROP 1 LAST HDL_POWER GND
J 1
(2650 -325);
DISPLAY 0.702128 (2650 -325);
PAINT GREEN (2650 -325);
DISPLAY INVISIBLE (2650 -325);
FORCEPROP 2 LAST CDS_LIB logical_power
J 0
(2625 -250);
DISPLAY INVISIBLE (2625 -250);
FORCEADD Q_CAP..1
(2625 -50);
FORCEPROP 1 LAST PACK_TYPE 0402
J 0
(2675 -200);
DISPLAY 0.510638 (2675 -200);
PAINT SKYBLUE (2675 -200);
FORCEPROP 1 LAST TOLERANCE 10%
J 0
(2675 -100);
DISPLAY 0.510638 (2675 -100);
PAINT SKYBLUE (2675 -100);
FORCEPROP 1 LAST MATERIAL X7R
J 0
(2675 -150);
DISPLAY 0.510638 (2675 -150);
PAINT SKYBLUE (2675 -150);
FORCEPROP 1 LAST PART_NUMBER CH4104K1B00
J 0
(2675 -250);
DISPLAY 0.510638 (2675 -250);
PAINT WHITE (2675 -250);
FORCEPROP 1 LAST VOLTAGE 25V
J 0
(2675 -50);
DISPLAY 0.510638 (2675 -50);
PAINT SKYBLUE (2675 -50);
FORCEPROP 1 LAST VALUE 0.1UF
J 0
(2675 0);
DISPLAY 0.510638 (2675 0);
PAINT SKYBLUE (2675 0);
FORCEPROP 1 LAST PATH I106
J 0
(2675 100);
DISPLAY 0.978723 (2675 100);
PAINT WHITE (2675 100);
DISPLAY INVISIBLE (2675 100);
FORCEPROP 2 LAST CDS_LIB pure_quanta
J 0
(2625 -50);
DISPLAY INVISIBLE (2625 -50);
FORCEPROP 1 LAST LOCATION C83
J 0
(2675 50);
DISPLAY 0.702128 (2675 50);
PAINT YELLOW (2675 50);
FORCEPROP 1 LASTPIN (2625 50) $PN 1
J 0
(2635 30);
DISPLAY 0.808511 (2635 30);
PAINT WHITE (2635 30);
FORCEPROP 1 LASTPIN (2625 -150) $PN 2
J 0
(2635 -170);
DISPLAY 0.808511 (2635 -170);
PAINT WHITE (2635 -170);
FORCEPROP 2 LAST $SEC 1
J 0
(2675 150);
DISPLAY 0.680851 (2675 150);
PAINT MONO (2675 150);
DISPLAY INVISIBLE (2675 150);
FORCEPROP 0 LAST CDS_SEC 1
J 0
(2675 150);
DISPLAY 0.680851 (2675 150);
PAINT MONO (2675 150);
DISPLAY INVISIBLE (2675 150);
FORCEADD UNIVERSAL_POWER..1
(2850 175);
FORCEPROP 3 LASTPIN (2850 125) SIG_NAME P3V3_RTC_AUX\g
J 0
(2860 135);
DISPLAY 0.659574 (2860 135);
PAINT MONO (2860 135);
DISPLAY INVISIBLE (2860 135);
FORCEPROP 1 LAST HDL_POWER P3V3_RTC_AUX
J 1
(2850 225);
DISPLAY 0.702128 (2850 225);
PAINT GREEN (2850 225);
FORCEPROP 1 LAST PATH I107
J 0
(2900 200);
DISPLAY 0.872340 (2900 200);
PAINT AQUA (2900 200);
DISPLAY INVISIBLE (2900 200);
FORCEPROP 2 LAST CDS_LIB logical_power
J 0
(2850 175);
DISPLAY INVISIBLE (2850 175);
FORCEADD Q_CAP..1
(2850 725);
FORCEPROP 1 LAST PACK_TYPE 0402
J 0
(2900 575);
DISPLAY 0.510638 (2900 575);
PAINT SKYBLUE (2900 575);
FORCEPROP 1 LAST VALUE 0.1UF
J 0
(2900 775);
DISPLAY 0.510638 (2900 775);
PAINT SKYBLUE (2900 775);
FORCEPROP 1 LAST TOLERANCE 10%
J 0
(2900 675);
DISPLAY 0.510638 (2900 675);
PAINT SKYBLUE (2900 675);
FORCEPROP 1 LAST MATERIAL X7R
J 0
(2900 625);
DISPLAY 0.510638 (2900 625);
PAINT SKYBLUE (2900 625);
FORCEPROP 1 LAST PART_NUMBER CH4104K1B00
J 0
(2825 500);
DISPLAY 0.510638 (2825 500);
PAINT WHITE (2825 500);
FORCEPROP 1 LAST VOLTAGE 25V
J 0
(2900 725);
DISPLAY 0.510638 (2900 725);
PAINT SKYBLUE (2900 725);
FORCEPROP 1 LAST PATH I118
J 0
(2900 875);
DISPLAY 0.978723 (2900 875);
PAINT WHITE (2900 875);
DISPLAY INVISIBLE (2900 875);
FORCEPROP 2 LAST CDS_LIB pure_quanta
J 0
(2850 725);
DISPLAY INVISIBLE (2850 725);
FORCEPROP 1 LAST $LOCATION C89
J 0
(2900 825);
DISPLAY 0.702128 (2900 825);
PAINT YELLOW (2900 825);
FORCEPROP 1 LASTPIN (2850 825) $PN 1
J 0
(2860 805);
DISPLAY 0.808511 (2860 805);
PAINT WHITE (2860 805);
FORCEPROP 1 LASTPIN (2850 625) $PN 2
J 0
(2860 605);
DISPLAY 0.808511 (2860 605);
PAINT WHITE (2860 605);
FORCEPROP 0 LAST CDS_LOCATION C89
J 0
(2900 875);
DISPLAY 0.680851 (2900 875);
DISPLAY INVISIBLE (2900 875);
FORCEPROP 2 LAST $SEC 1
J 0
(2900 925);
DISPLAY 0.680851 (2900 925);
PAINT MONO (2900 925);
DISPLAY INVISIBLE (2900 925);
FORCEPROP 0 LAST CDS_SEC 1
J 0
(2900 925);
DISPLAY 0.680851 (2900 925);
PAINT MONO (2900 925);
DISPLAY INVISIBLE (2900 925);
FORCEADD Q_CAP..1
(3050 725);
FORCEPROP 1 LAST PACK_TYPE 0402
J 0
(3100 575);
DISPLAY 0.510638 (3100 575);
PAINT SKYBLUE (3100 575);
FORCEPROP 1 LAST TOLERANCE 10%
J 0
(3100 675);
DISPLAY 0.510638 (3100 675);
PAINT SKYBLUE (3100 675);
FORCEPROP 1 LAST MATERIAL X7R
J 0
(3100 625);
DISPLAY 0.510638 (3100 625);
PAINT SKYBLUE (3100 625);
FORCEPROP 1 LAST VOLTAGE 25V
J 0
(3100 725);
DISPLAY 0.510638 (3100 725);
PAINT SKYBLUE (3100 725);
FORCEPROP 1 LAST VALUE 0.1UF
J 0
(3100 775);
DISPLAY 0.510638 (3100 775);
PAINT SKYBLUE (3100 775);
FORCEPROP 1 LAST PATH I119
J 0
(3100 875);
DISPLAY 0.978723 (3100 875);
PAINT WHITE (3100 875);
DISPLAY INVISIBLE (3100 875);
FORCEPROP 1 LAST PART_NUMBER CH4104K1B00
J 0
(3100 575);
DISPLAY 0.510638 (3100 575);
PAINT WHITE (3100 575);
DISPLAY INVISIBLE (3100 575);
FORCEPROP 2 LAST CDS_LIB pure_quanta
J 0
(3050 725);
DISPLAY INVISIBLE (3050 725);
FORCEPROP 1 LAST LOCATION C95
J 0
(3100 825);
DISPLAY 0.702128 (3100 825);
PAINT YELLOW (3100 825);
FORCEPROP 1 LASTPIN (3050 825) $PN 1
J 0
(3060 805);
DISPLAY 0.808511 (3060 805);
PAINT WHITE (3060 805);
FORCEPROP 1 LASTPIN (3050 625) $PN 2
J 0
(3060 605);
DISPLAY 0.808511 (3060 605);
PAINT WHITE (3060 605);
FORCEPROP 2 LAST $SEC 1
J 0
(3100 925);
DISPLAY 0.680851 (3100 925);
PAINT MONO (3100 925);
DISPLAY INVISIBLE (3100 925);
FORCEPROP 0 LAST CDS_SEC 1
J 0
(3100 925);
DISPLAY 0.680851 (3100 925);
PAINT MONO (3100 925);
DISPLAY INVISIBLE (3100 925);
FORCEADD Q_CAP..1
(2775 1275);
FORCEPROP 1 LAST PACK_TYPE 0402
J 0
(2825 1125);
DISPLAY 0.510638 (2825 1125);
PAINT SKYBLUE (2825 1125);
FORCEPROP 1 LAST TOLERANCE 10%
J 0
(2825 1225);
DISPLAY 0.510638 (2825 1225);
PAINT SKYBLUE (2825 1225);
FORCEPROP 1 LAST MATERIAL X7R
J 0
(2825 1175);
DISPLAY 0.510638 (2825 1175);
PAINT SKYBLUE (2825 1175);
FORCEPROP 1 LAST VOLTAGE 25V
J 0
(2825 1275);
DISPLAY 0.510638 (2825 1275);
PAINT SKYBLUE (2825 1275);
FORCEPROP 1 LAST VALUE 0.1UF
J 0
(2825 1325);
DISPLAY 0.510638 (2825 1325);
PAINT SKYBLUE (2825 1325);
FORCEPROP 1 LAST PATH I120
J 0
(2825 1425);
DISPLAY 0.978723 (2825 1425);
PAINT WHITE (2825 1425);
DISPLAY INVISIBLE (2825 1425);
FORCEPROP 1 LAST PART_NUMBER CH4104K1B00
J 0
(2825 1125);
DISPLAY 0.510638 (2825 1125);
PAINT WHITE (2825 1125);
DISPLAY INVISIBLE (2825 1125);
FORCEPROP 2 LAST CDS_LIB pure_quanta
J 0
(2775 1275);
DISPLAY INVISIBLE (2775 1275);
FORCEPROP 1 LAST LOCATION C85
J 0
(2825 1375);
DISPLAY 0.702128 (2825 1375);
PAINT YELLOW (2825 1375);
FORCEPROP 1 LASTPIN (2775 1375) $PN 1
J 0
(2785 1355);
DISPLAY 0.808511 (2785 1355);
PAINT WHITE (2785 1355);
FORCEPROP 1 LASTPIN (2775 1175) $PN 2
J 0
(2785 1155);
DISPLAY 0.808511 (2785 1155);
PAINT WHITE (2785 1155);
FORCEPROP 0 LAST $SEC 1
J 0
(2825 1425);
DISPLAY 0.680851 (2825 1425);
PAINT MONO (2825 1425);
DISPLAY INVISIBLE (2825 1425);
FORCEPROP 0 LAST CDS_SEC 1
J 0
(2825 1425);
DISPLAY 0.680851 (2825 1425);
DISPLAY INVISIBLE (2825 1425);
FORCEADD UNIVERSAL_GND..1
(2775 1000);
FORCEPROP 3 LASTPIN (2775 1050) SIG_NAME GND\g
J 0
(2785 1060);
DISPLAY 0.659574 (2785 1060);
PAINT MONO (2785 1060);
DISPLAY INVISIBLE (2785 1060);
FORCEPROP 1 LAST PATH I121
J 0
(2850 1000);
DISPLAY 0.872340 (2850 1000);
PAINT AQUA (2850 1000);
DISPLAY INVISIBLE (2850 1000);
FORCEPROP 1 LAST HDL_POWER GND
J 1
(2800 925);
DISPLAY 0.702128 (2800 925);
PAINT GREEN (2800 925);
DISPLAY INVISIBLE (2800 925);
FORCEPROP 2 LAST CDS_LIB logical_power
J 0
(2775 1000);
DISPLAY INVISIBLE (2775 1000);
FORCEADD UNIVERSAL_POWER..1
(2775 1550);
FORCEPROP 3 LASTPIN (2775 1500) SIG_NAME P3V3_RGM\g
J 0
(2785 1510);
DISPLAY 0.659574 (2785 1510);
PAINT MONO (2785 1510);
DISPLAY INVISIBLE (2785 1510);
FORCEPROP 1 LAST HDL_POWER P3V3_RGM
J 1
(2775 1600);
DISPLAY 0.702128 (2775 1600);
PAINT GREEN (2775 1600);
FORCEPROP 1 LAST PATH I122
J 0
(2825 1575);
DISPLAY 0.872340 (2825 1575);
PAINT AQUA (2825 1575);
DISPLAY INVISIBLE (2825 1575);
FORCEPROP 2 LAST CDS_LIB logical_power
J 0
(2775 1550);
DISPLAY INVISIBLE (2775 1550);
FORCEADD Q_CAP..1
(2825 1875);
FORCEPROP 1 LAST PACK_TYPE 0402
J 0
(2875 1725);
DISPLAY 0.510638 (2875 1725);
PAINT SKYBLUE (2875 1725);
FORCEPROP 1 LAST VALUE 0.1UF
J 0
(2875 1925);
DISPLAY 0.510638 (2875 1925);
PAINT SKYBLUE (2875 1925);
FORCEPROP 1 LAST TOLERANCE 10%
J 0
(2875 1825);
DISPLAY 0.510638 (2875 1825);
PAINT SKYBLUE (2875 1825);
FORCEPROP 1 LAST MATERIAL X7R
J 0
(2875 1775);
DISPLAY 0.510638 (2875 1775);
PAINT SKYBLUE (2875 1775);
FORCEPROP 1 LAST PART_NUMBER CH4104K1B00
J 0
(2825 1650);
DISPLAY 0.510638 (2825 1650);
PAINT WHITE (2825 1650);
FORCEPROP 1 LAST VOLTAGE 25V
J 0
(2875 1875);
DISPLAY 0.510638 (2875 1875);
PAINT SKYBLUE (2875 1875);
FORCEPROP 1 LAST PATH I123
J 0
(2875 2025);
DISPLAY 0.978723 (2875 2025);
PAINT WHITE (2875 2025);
DISPLAY INVISIBLE (2875 2025);
FORCEPROP 2 LAST CDS_LIB pure_quanta
J 0
(2825 1875);
DISPLAY INVISIBLE (2825 1875);
FORCEPROP 1 LAST LOCATION C88
J 0
(2875 1975);
DISPLAY 0.702128 (2875 1975);
PAINT YELLOW (2875 1975);
FORCEPROP 1 LASTPIN (2825 1975) $PN 1
J 0
(2835 1955);
DISPLAY 0.808511 (2835 1955);
PAINT WHITE (2835 1955);
FORCEPROP 1 LASTPIN (2825 1775) $PN 2
J 0
(2835 1755);
DISPLAY 0.808511 (2835 1755);
PAINT WHITE (2835 1755);
FORCEPROP 2 LAST $SEC 1
J 0
(2875 2075);
DISPLAY 0.680851 (2875 2075);
PAINT MONO (2875 2075);
DISPLAY INVISIBLE (2875 2075);
FORCEPROP 0 LAST CDS_SEC 1
J 0
(2875 2075);
DISPLAY 0.680851 (2875 2075);
PAINT MONO (2875 2075);
DISPLAY INVISIBLE (2875 2075);
FORCEADD Q_CAP..1
(3025 1875);
FORCEPROP 1 LAST PACK_TYPE 0402
J 0
(3075 1725);
DISPLAY 0.510638 (3075 1725);
PAINT SKYBLUE (3075 1725);
FORCEPROP 1 LAST VALUE 0.1UF
J 0
(3075 1925);
DISPLAY 0.510638 (3075 1925);
PAINT SKYBLUE (3075 1925);
FORCEPROP 1 LAST TOLERANCE 10%
J 0
(3075 1825);
DISPLAY 0.510638 (3075 1825);
PAINT SKYBLUE (3075 1825);
FORCEPROP 1 LAST MATERIAL X7R
J 0
(3075 1775);
DISPLAY 0.510638 (3075 1775);
PAINT SKYBLUE (3075 1775);
FORCEPROP 1 LAST VOLTAGE 25V
J 0
(3075 1875);
DISPLAY 0.510638 (3075 1875);
PAINT SKYBLUE (3075 1875);
FORCEPROP 1 LAST PATH I124
J 0
(3075 2025);
DISPLAY 0.978723 (3075 2025);
PAINT WHITE (3075 2025);
DISPLAY INVISIBLE (3075 2025);
FORCEPROP 1 LAST PART_NUMBER CH4104K1B00
J 0
(3075 1725);
DISPLAY 0.510638 (3075 1725);
PAINT WHITE (3075 1725);
DISPLAY INVISIBLE (3075 1725);
FORCEPROP 2 LAST CDS_LIB pure_quanta
J 0
(3025 1875);
DISPLAY INVISIBLE (3025 1875);
FORCEPROP 1 LAST LOCATION C94
J 0
(3075 1975);
DISPLAY 0.702128 (3075 1975);
PAINT YELLOW (3075 1975);
FORCEPROP 1 LASTPIN (3025 1975) $PN 1
J 0
(3035 1955);
DISPLAY 0.808511 (3035 1955);
PAINT WHITE (3035 1955);
FORCEPROP 1 LASTPIN (3025 1775) $PN 2
J 0
(3035 1755);
DISPLAY 0.808511 (3035 1755);
PAINT WHITE (3035 1755);
FORCEPROP 2 LAST $SEC 1
J 0
(3075 2075);
DISPLAY 0.680851 (3075 2075);
PAINT MONO (3075 2075);
DISPLAY INVISIBLE (3075 2075);
FORCEPROP 0 LAST CDS_SEC 1
J 0
(3075 2075);
DISPLAY 0.680851 (3075 2075);
PAINT MONO (3075 2075);
DISPLAY INVISIBLE (3075 2075);
FORCEADD UNIVERSAL_POWER..1
(3200 375);
FORCEPROP 3 LASTPIN (3200 325) SIG_NAME PGPPA_BMC_AUX\g
J 0
(3210 335);
DISPLAY 0.659574 (3210 335);
PAINT MONO (3210 335);
DISPLAY INVISIBLE (3210 335);
FORCEPROP 1 LAST HDL_POWER PGPPA_BMC_AUX
J 1
(3200 425);
DISPLAY 0.702128 (3200 425);
PAINT GREEN (3200 425);
FORCEPROP 1 LAST PATH I125
J 0
(3250 400);
DISPLAY 0.872340 (3250 400);
PAINT AQUA (3250 400);
DISPLAY INVISIBLE (3250 400);
FORCEPROP 2 LAST CDS_LIB logical_power
J 0
(3200 375);
DISPLAY INVISIBLE (3200 375);
FORCEADD Q_CAP..1
(3250 725);
FORCEPROP 1 LAST VALUE 0.1UF
J 0
(3300 775);
DISPLAY 0.510638 (3300 775);
PAINT SKYBLUE (3300 775);
FORCEPROP 1 LAST VOLTAGE 25V
J 0
(3300 725);
DISPLAY 0.510638 (3300 725);
PAINT SKYBLUE (3300 725);
FORCEPROP 1 LAST PACK_TYPE 0402
J 0
(3300 575);
DISPLAY 0.510638 (3300 575);
PAINT SKYBLUE (3300 575);
FORCEPROP 1 LAST MATERIAL X7R
J 0
(3300 625);
DISPLAY 0.510638 (3300 625);
PAINT SKYBLUE (3300 625);
FORCEPROP 1 LAST TOLERANCE 10%
J 0
(3300 675);
DISPLAY 0.510638 (3300 675);
PAINT SKYBLUE (3300 675);
FORCEPROP 1 LAST PATH I126
J 0
(3300 875);
DISPLAY 0.978723 (3300 875);
PAINT WHITE (3300 875);
DISPLAY INVISIBLE (3300 875);
FORCEPROP 1 LAST PART_NUMBER CH4104K1B00
J 0
(3300 575);
DISPLAY 0.510638 (3300 575);
PAINT WHITE (3300 575);
DISPLAY INVISIBLE (3300 575);
FORCEPROP 2 LAST CDS_LIB pure_quanta
J 0
(3250 725);
DISPLAY INVISIBLE (3250 725);
FORCEPROP 1 LAST LOCATION C102
J 0
(3300 825);
DISPLAY 0.702128 (3300 825);
PAINT YELLOW (3300 825);
FORCEPROP 1 LASTPIN (3250 825) $PN 1
J 0
(3260 805);
DISPLAY 0.808511 (3260 805);
PAINT WHITE (3260 805);
FORCEPROP 1 LASTPIN (3250 625) $PN 2
J 0
(3260 605);
DISPLAY 0.808511 (3260 605);
PAINT WHITE (3260 605);
FORCEPROP 2 LAST $SEC 1
J 0
(3300 925);
DISPLAY 0.680851 (3300 925);
PAINT MONO (3300 925);
DISPLAY INVISIBLE (3300 925);
FORCEPROP 0 LAST CDS_SEC 1
J 0
(3300 925);
DISPLAY 0.680851 (3300 925);
PAINT MONO (3300 925);
DISPLAY INVISIBLE (3300 925);
FORCEADD Q_CAP..1
(3425 725);
FORCEPROP 1 LAST PACK_TYPE C0402
J 0
(3450 575);
DISPLAY 0.510638 (3450 575);
PAINT SKYBLUE (3450 575);
FORCEPROP 1 LAST TOLERANCE 10%
J 0
(3475 675);
DISPLAY 0.510638 (3475 675);
PAINT SKYBLUE (3475 675);
FORCEPROP 1 LAST MATERIAL X6S
J 0
(3475 625);
DISPLAY 0.510638 (3475 625);
PAINT SKYBLUE (3475 625);
FORCEPROP 1 LAST VALUE 1UF
J 0
(3475 775);
DISPLAY 0.510638 (3475 775);
PAINT SKYBLUE (3475 775);
FORCEPROP 1 LAST VOLTAGE 25V
J 0
(3475 725);
DISPLAY 0.510638 (3475 725);
PAINT SKYBLUE (3475 725);
FORCEPROP 1 LAST PATH I127
J 0
(3475 875);
DISPLAY 0.978723 (3475 875);
PAINT WHITE (3475 875);
DISPLAY INVISIBLE (3475 875);
FORCEPROP 1 LAST PART_NUMBER CH5104KEB02
J 0
(3475 575);
DISPLAY 0.510638 (3475 575);
PAINT WHITE (3475 575);
DISPLAY INVISIBLE (3475 575);
FORCEPROP 2 LAST CDS_LIB pure_quanta
J 0
(3425 725);
DISPLAY INVISIBLE (3425 725);
FORCEPROP 1 LAST LOCATION C106
J 0
(3475 825);
DISPLAY 0.702128 (3475 825);
PAINT YELLOW (3475 825);
FORCEPROP 1 LASTPIN (3425 825) $PN 1
J 0
(3435 805);
DISPLAY 0.808511 (3435 805);
PAINT WHITE (3435 805);
FORCEPROP 1 LASTPIN (3425 625) $PN 2
J 0
(3435 605);
DISPLAY 0.808511 (3435 605);
PAINT WHITE (3435 605);
FORCEPROP 0 LAST $SEC 1
J 0
(3475 875);
DISPLAY 0.680851 (3475 875);
PAINT MONO (3475 875);
DISPLAY INVISIBLE (3475 875);
FORCEPROP 0 LAST CDS_SEC 1
J 0
(3475 875);
DISPLAY 0.680851 (3475 875);
DISPLAY INVISIBLE (3475 875);
FORCEADD Q_CAP..1
(3600 725);
FORCEPROP 1 LAST PACK_TYPE C0402
J 0
(3625 575);
DISPLAY 0.510638 (3625 575);
PAINT SKYBLUE (3625 575);
FORCEPROP 1 LAST TOLERANCE 10%
J 0
(3650 675);
DISPLAY 0.510638 (3650 675);
PAINT SKYBLUE (3650 675);
FORCEPROP 1 LAST MATERIAL X6S
J 0
(3650 625);
DISPLAY 0.510638 (3650 625);
PAINT SKYBLUE (3650 625);
FORCEPROP 1 LAST PART_NUMBER CH5104KEB02
J 0
(3575 500);
DISPLAY 0.510638 (3575 500);
PAINT WHITE (3575 500);
FORCEPROP 1 LAST VALUE 1UF
J 0
(3650 775);
DISPLAY 0.510638 (3650 775);
PAINT SKYBLUE (3650 775);
FORCEPROP 1 LAST VOLTAGE 25V
J 0
(3650 725);
DISPLAY 0.510638 (3650 725);
PAINT SKYBLUE (3650 725);
FORCEPROP 1 LAST PATH I128
J 0
(3650 875);
DISPLAY 0.978723 (3650 875);
PAINT WHITE (3650 875);
DISPLAY INVISIBLE (3650 875);
FORCEPROP 2 LAST CDS_LIB pure_quanta
J 0
(3600 725);
DISPLAY INVISIBLE (3600 725);
FORCEPROP 1 LAST LOCATION C111
J 0
(3650 825);
DISPLAY 0.702128 (3650 825);
PAINT YELLOW (3650 825);
FORCEPROP 1 LASTPIN (3600 825) $PN 1
J 0
(3610 805);
DISPLAY 0.808511 (3610 805);
PAINT WHITE (3610 805);
FORCEPROP 1 LASTPIN (3600 625) $PN 2
J 0
(3610 605);
DISPLAY 0.808511 (3610 605);
PAINT WHITE (3610 605);
FORCEPROP 2 LAST $SEC 1
J 0
(3650 925);
DISPLAY 0.680851 (3650 925);
PAINT MONO (3650 925);
DISPLAY INVISIBLE (3650 925);
FORCEPROP 0 LAST CDS_SEC 1
J 0
(3650 925);
DISPLAY 0.680851 (3650 925);
PAINT MONO (3650 925);
DISPLAY INVISIBLE (3650 925);
FORCEADD Q_CAP..1
(3775 725);
FORCEPROP 1 LAST PACK_TYPE C0402
J 0
(3800 575);
DISPLAY 0.510638 (3800 575);
PAINT SKYBLUE (3800 575);
FORCEPROP 1 LAST TOLERANCE 10%
J 0
(3825 675);
DISPLAY 0.510638 (3825 675);
PAINT SKYBLUE (3825 675);
FORCEPROP 1 LAST MATERIAL X6S
J 0
(3825 625);
DISPLAY 0.510638 (3825 625);
PAINT SKYBLUE (3825 625);
FORCEPROP 1 LAST VALUE 1UF
J 0
(3825 775);
DISPLAY 0.510638 (3825 775);
PAINT SKYBLUE (3825 775);
FORCEPROP 1 LAST VOLTAGE 25V
J 0
(3825 725);
DISPLAY 0.510638 (3825 725);
PAINT SKYBLUE (3825 725);
FORCEPROP 1 LAST PATH I129
J 0
(3825 875);
DISPLAY 0.978723 (3825 875);
PAINT WHITE (3825 875);
DISPLAY INVISIBLE (3825 875);
FORCEPROP 1 LAST PART_NUMBER CH5104KEB02
J 0
(3825 575);
DISPLAY 0.510638 (3825 575);
PAINT WHITE (3825 575);
DISPLAY INVISIBLE (3825 575);
FORCEPROP 2 LAST CDS_LIB pure_quanta
J 0
(3775 725);
DISPLAY INVISIBLE (3775 725);
FORCEPROP 1 LAST LOCATION C116
J 0
(3825 825);
DISPLAY 0.702128 (3825 825);
PAINT YELLOW (3825 825);
FORCEPROP 1 LASTPIN (3775 825) $PN 1
J 0
(3785 805);
DISPLAY 0.808511 (3785 805);
PAINT WHITE (3785 805);
FORCEPROP 1 LASTPIN (3775 625) $PN 2
J 0
(3785 605);
DISPLAY 0.808511 (3785 605);
PAINT WHITE (3785 605);
FORCEPROP 2 LAST $SEC 1
J 0
(3825 925);
DISPLAY 0.680851 (3825 925);
PAINT MONO (3825 925);
DISPLAY INVISIBLE (3825 925);
FORCEPROP 0 LAST CDS_SEC 1
J 0
(3825 925);
DISPLAY 0.680851 (3825 925);
PAINT MONO (3825 925);
DISPLAY INVISIBLE (3825 925);
FORCEADD Q_CAP..1
(3975 725);
FORCEPROP 1 LAST TOLERANCE 20%
J 0
(4025 675);
DISPLAY 0.510638 (4025 675);
PAINT SKYBLUE (4025 675);
FORCEPROP 1 LAST MATERIAL X6S
J 0
(4025 625);
DISPLAY 0.510638 (4025 625);
PAINT SKYBLUE (4025 625);
FORCEPROP 1 LAST VALUE 22UF
J 0
(4025 775);
DISPLAY 0.510638 (4025 775);
PAINT SKYBLUE (4025 775);
FORCEPROP 1 LAST PACK_TYPE C0603
J 0
(4025 575);
DISPLAY 0.510638 (4025 575);
PAINT SKYBLUE (4025 575);
FORCEPROP 1 LAST VOLTAGE 6.3V
J 0
(4025 725);
DISPLAY 0.510638 (4025 725);
PAINT SKYBLUE (4025 725);
FORCEPROP 1 LAST PATH I131
J 0
(4025 875);
DISPLAY 0.978723 (4025 875);
PAINT WHITE (4025 875);
DISPLAY INVISIBLE (4025 875);
FORCEPROP 1 LAST PART_NUMBER CH6221ME900
J 0
(4025 575);
DISPLAY 0.510638 (4025 575);
PAINT WHITE (4025 575);
DISPLAY INVISIBLE (4025 575);
FORCEPROP 2 LAST CDS_LIB pure_quanta
J 0
(3975 725);
DISPLAY INVISIBLE (3975 725);
FORCEPROP 1 LAST LOCATION C121
J 0
(4025 825);
DISPLAY 0.702128 (4025 825);
PAINT YELLOW (4025 825);
FORCEPROP 1 LASTPIN (3975 825) $PN 1
J 0
(3985 805);
DISPLAY 0.808511 (3985 805);
PAINT WHITE (3985 805);
FORCEPROP 1 LASTPIN (3975 625) $PN 2
J 0
(3985 605);
DISPLAY 0.808511 (3985 605);
PAINT WHITE (3985 605);
FORCEPROP 0 LAST $SEC 1
J 0
(4025 875);
DISPLAY 0.680851 (4025 875);
PAINT MONO (4025 875);
DISPLAY INVISIBLE (4025 875);
FORCEPROP 0 LAST CDS_SEC 1
J 0
(4025 875);
DISPLAY 0.680851 (4025 875);
DISPLAY INVISIBLE (4025 875);
FORCEADD Q_CAP..1
(3225 1875);
FORCEPROP 1 LAST PACK_TYPE 0402
J 0
(3275 1725);
DISPLAY 0.510638 (3275 1725);
PAINT SKYBLUE (3275 1725);
FORCEPROP 1 LAST MATERIAL X7R
J 0
(3275 1775);
DISPLAY 0.510638 (3275 1775);
PAINT SKYBLUE (3275 1775);
FORCEPROP 1 LAST TOLERANCE 10%
J 0
(3275 1825);
DISPLAY 0.510638 (3275 1825);
PAINT SKYBLUE (3275 1825);
FORCEPROP 1 LAST VOLTAGE 25V
J 0
(3275 1875);
DISPLAY 0.510638 (3275 1875);
PAINT SKYBLUE (3275 1875);
FORCEPROP 1 LAST VALUE 0.1UF
J 0
(3275 1925);
DISPLAY 0.510638 (3275 1925);
PAINT SKYBLUE (3275 1925);
FORCEPROP 1 LAST PATH I132
J 0
(3275 2025);
DISPLAY 0.978723 (3275 2025);
PAINT WHITE (3275 2025);
DISPLAY INVISIBLE (3275 2025);
FORCEPROP 1 LAST PART_NUMBER CH4104K1B00
J 0
(3275 1725);
DISPLAY 0.510638 (3275 1725);
PAINT WHITE (3275 1725);
DISPLAY INVISIBLE (3275 1725);
FORCEPROP 2 LAST CDS_LIB pure_quanta
J 0
(3225 1875);
DISPLAY INVISIBLE (3225 1875);
FORCEPROP 1 LAST LOCATION C101
J 0
(3275 1975);
DISPLAY 0.702128 (3275 1975);
PAINT YELLOW (3275 1975);
FORCEPROP 1 LASTPIN (3225 1975) $PN 1
J 0
(3235 1955);
DISPLAY 0.808511 (3235 1955);
PAINT WHITE (3235 1955);
FORCEPROP 1 LASTPIN (3225 1775) $PN 2
J 0
(3235 1755);
DISPLAY 0.808511 (3235 1755);
PAINT WHITE (3235 1755);
FORCEPROP 2 LAST $SEC 1
J 0
(3275 2075);
DISPLAY 0.680851 (3275 2075);
PAINT MONO (3275 2075);
DISPLAY INVISIBLE (3275 2075);
FORCEPROP 0 LAST CDS_SEC 1
J 0
(3275 2075);
DISPLAY 0.680851 (3275 2075);
PAINT MONO (3275 2075);
DISPLAY INVISIBLE (3275 2075);
FORCEADD Q_CAP..1
(3575 1875);
FORCEPROP 1 LAST VALUE 1UF
J 0
(3625 1925);
DISPLAY 0.510638 (3625 1925);
PAINT SKYBLUE (3625 1925);
FORCEPROP 1 LAST MATERIAL X6S
J 0
(3625 1775);
DISPLAY 0.510638 (3625 1775);
PAINT SKYBLUE (3625 1775);
FORCEPROP 1 LAST TOLERANCE 10%
J 0
(3625 1825);
DISPLAY 0.510638 (3625 1825);
PAINT SKYBLUE (3625 1825);
FORCEPROP 1 LAST PART_NUMBER CH5104KEB02
J 0
(3575 1650);
DISPLAY 0.510638 (3575 1650);
PAINT WHITE (3575 1650);
FORCEPROP 1 LAST PACK_TYPE C0402
J 0
(3600 1725);
DISPLAY 0.510638 (3600 1725);
PAINT SKYBLUE (3600 1725);
FORCEPROP 1 LAST VOLTAGE 25V
J 0
(3625 1875);
DISPLAY 0.510638 (3625 1875);
PAINT SKYBLUE (3625 1875);
FORCEPROP 1 LAST PATH I133
J 0
(3625 2025);
DISPLAY 0.978723 (3625 2025);
PAINT WHITE (3625 2025);
DISPLAY INVISIBLE (3625 2025);
FORCEPROP 2 LAST CDS_LIB pure_quanta
J 0
(3575 1875);
DISPLAY INVISIBLE (3575 1875);
FORCEPROP 1 LAST LOCATION C110
J 0
(3625 1975);
DISPLAY 0.702128 (3625 1975);
PAINT YELLOW (3625 1975);
FORCEPROP 1 LASTPIN (3575 1975) $PN 1
J 0
(3585 1955);
DISPLAY 0.808511 (3585 1955);
PAINT WHITE (3585 1955);
FORCEPROP 1 LASTPIN (3575 1775) $PN 2
J 0
(3585 1755);
DISPLAY 0.808511 (3585 1755);
PAINT WHITE (3585 1755);
FORCEPROP 2 LAST $SEC 1
J 0
(3625 2075);
DISPLAY 0.680851 (3625 2075);
PAINT MONO (3625 2075);
DISPLAY INVISIBLE (3625 2075);
FORCEPROP 0 LAST CDS_SEC 1
J 0
(3625 2075);
DISPLAY 0.680851 (3625 2075);
PAINT MONO (3625 2075);
DISPLAY INVISIBLE (3625 2075);
FORCEADD UNIVERSAL_GND..1
(4050 1600);
FORCEPROP 3 LASTPIN (4050 1650) SIG_NAME GND\g
J 0
(4060 1660);
DISPLAY 0.659574 (4060 1660);
PAINT MONO (4060 1660);
DISPLAY INVISIBLE (4060 1660);
FORCEPROP 1 LAST PATH I134
J 0
(4125 1600);
DISPLAY 0.872340 (4125 1600);
PAINT AQUA (4125 1600);
DISPLAY INVISIBLE (4125 1600);
FORCEPROP 1 LAST HDL_POWER GND
J 1
(4075 1525);
DISPLAY 0.702128 (4075 1525);
PAINT GREEN (4075 1525);
DISPLAY INVISIBLE (4075 1525);
FORCEPROP 2 LAST CDS_LIB logical_power
J 0
(4050 1600);
DISPLAY INVISIBLE (4050 1600);
FORCEADD Q_CAP..1
(3750 1875);
FORCEPROP 1 LAST VOLTAGE 25V
J 0
(3800 1875);
DISPLAY 0.510638 (3800 1875);
PAINT SKYBLUE (3800 1875);
FORCEPROP 1 LAST VALUE 1UF
J 0
(3800 1925);
DISPLAY 0.510638 (3800 1925);
PAINT SKYBLUE (3800 1925);
FORCEPROP 1 LAST TOLERANCE 10%
J 0
(3800 1825);
DISPLAY 0.510638 (3800 1825);
PAINT SKYBLUE (3800 1825);
FORCEPROP 1 LAST PACK_TYPE C0402
J 0
(3775 1725);
DISPLAY 0.510638 (3775 1725);
PAINT SKYBLUE (3775 1725);
FORCEPROP 1 LAST MATERIAL X6S
J 0
(3800 1775);
DISPLAY 0.510638 (3800 1775);
PAINT SKYBLUE (3800 1775);
FORCEPROP 1 LAST PATH I135
J 0
(3800 2025);
DISPLAY 0.978723 (3800 2025);
PAINT WHITE (3800 2025);
DISPLAY INVISIBLE (3800 2025);
FORCEPROP 1 LAST PART_NUMBER CH5104KEB02
J 0
(3800 1725);
DISPLAY 0.510638 (3800 1725);
PAINT WHITE (3800 1725);
DISPLAY INVISIBLE (3800 1725);
FORCEPROP 2 LAST CDS_LIB pure_quanta
J 0
(3750 1875);
DISPLAY INVISIBLE (3750 1875);
FORCEPROP 1 LAST LOCATION C115
J 0
(3800 1975);
DISPLAY 0.702128 (3800 1975);
PAINT YELLOW (3800 1975);
FORCEPROP 1 LASTPIN (3750 1975) $PN 1
J 0
(3760 1955);
DISPLAY 0.808511 (3760 1955);
PAINT WHITE (3760 1955);
FORCEPROP 1 LASTPIN (3750 1775) $PN 2
J 0
(3760 1755);
DISPLAY 0.808511 (3760 1755);
PAINT WHITE (3760 1755);
FORCEPROP 2 LAST $SEC 1
J 0
(3800 2075);
DISPLAY 0.680851 (3800 2075);
PAINT MONO (3800 2075);
DISPLAY INVISIBLE (3800 2075);
FORCEPROP 0 LAST CDS_SEC 1
J 0
(3800 2075);
DISPLAY 0.680851 (3800 2075);
PAINT MONO (3800 2075);
DISPLAY INVISIBLE (3800 2075);
FORCEADD UNIVERSAL_GND..1
(4050 2225);
FORCEPROP 3 LASTPIN (4050 2275) SIG_NAME GND\g
J 0
(4060 2285);
DISPLAY 0.659574 (4060 2285);
PAINT MONO (4060 2285);
DISPLAY INVISIBLE (4060 2285);
FORCEPROP 1 LAST PATH I137
J 0
(4125 2225);
DISPLAY 0.872340 (4125 2225);
PAINT AQUA (4125 2225);
DISPLAY INVISIBLE (4125 2225);
FORCEPROP 1 LAST HDL_POWER GND
J 1
(4075 2150);
DISPLAY 0.702128 (4075 2150);
PAINT GREEN (4075 2150);
DISPLAY INVISIBLE (4075 2150);
FORCEPROP 2 LAST CDS_LIB logical_power
J 0
(4050 2225);
DISPLAY INVISIBLE (4050 2225);
FORCEADD Q_CAP..1
(4175 725);
FORCEPROP 1 LAST TOLERANCE 20%
J 0
(4225 675);
DISPLAY 0.510638 (4225 675);
PAINT SKYBLUE (4225 675);
FORCEPROP 1 LAST MATERIAL X6S
J 0
(4225 625);
DISPLAY 0.510638 (4225 625);
PAINT SKYBLUE (4225 625);
FORCEPROP 1 LAST PART_NUMBER CH6221ME900
J 0
(4225 575);
DISPLAY 0.510638 (4225 575);
PAINT WHITE (4225 575);
FORCEPROP 1 LAST VALUE 22UF
J 0
(4225 775);
DISPLAY 0.510638 (4225 775);
PAINT SKYBLUE (4225 775);
FORCEPROP 1 LAST PACK_TYPE C0603
J 0
(4225 525);
DISPLAY 0.510638 (4225 525);
PAINT SKYBLUE (4225 525);
FORCEPROP 1 LAST VOLTAGE 6.3V
J 0
(4225 725);
DISPLAY 0.510638 (4225 725);
PAINT SKYBLUE (4225 725);
FORCEPROP 1 LAST PATH I143
J 0
(4225 875);
DISPLAY 0.978723 (4225 875);
PAINT WHITE (4225 875);
DISPLAY INVISIBLE (4225 875);
FORCEPROP 2 LAST CDS_LIB pure_quanta
J 0
(4175 725);
DISPLAY INVISIBLE (4175 725);
FORCEPROP 1 LAST LOCATION C126
J 0
(4225 825);
DISPLAY 0.702128 (4225 825);
PAINT YELLOW (4225 825);
FORCEPROP 1 LASTPIN (4175 825) $PN 1
J 0
(4185 805);
DISPLAY 0.808511 (4185 805);
PAINT WHITE (4185 805);
FORCEPROP 1 LASTPIN (4175 625) $PN 2
J 0
(4185 605);
DISPLAY 0.808511 (4185 605);
PAINT WHITE (4185 605);
FORCEPROP 0 LAST $SEC 1
J 0
(4225 875);
DISPLAY 0.680851 (4225 875);
PAINT MONO (4225 875);
DISPLAY INVISIBLE (4225 875);
FORCEPROP 0 LAST CDS_SEC 1
J 0
(4225 875);
DISPLAY 0.680851 (4225 875);
DISPLAY INVISIBLE (4225 875);
FORCEADD UNIVERSAL_POWER..1
(4275 975);
FORCEPROP 3 LASTPIN (4275 925) SIG_NAME P1V8_AUX\g
J 0
(4285 935);
DISPLAY 0.659574 (4285 935);
PAINT MONO (4285 935);
DISPLAY INVISIBLE (4285 935);
FORCEPROP 1 LAST HDL_POWER P1V8_AUX
J 1
(4275 1025);
DISPLAY 0.702128 (4275 1025);
PAINT GREEN (4275 1025);
FORCEPROP 1 LAST PATH I144
J 0
(4325 1000);
DISPLAY 0.872340 (4325 1000);
PAINT AQUA (4325 1000);
DISPLAY INVISIBLE (4325 1000);
FORCEPROP 2 LAST CDS_LIB logical_power
J 0
(4275 975);
DISPLAY INVISIBLE (4275 975);
FORCEADD UNIVERSAL_POWER..1
(4250 2125);
FORCEPROP 3 LASTPIN (4250 2075) SIG_NAME P3V3_AUX\g
J 0
(4260 2085);
DISPLAY 0.659574 (4260 2085);
PAINT MONO (4260 2085);
DISPLAY INVISIBLE (4260 2085);
FORCEPROP 1 LAST HDL_POWER P3V3_AUX
J 1
(4250 2175);
DISPLAY 0.702128 (4250 2175);
PAINT GREEN (4250 2175);
FORCEPROP 1 LAST PATH I146
J 0
(4300 2150);
DISPLAY 0.872340 (4300 2150);
PAINT AQUA (4300 2150);
DISPLAY INVISIBLE (4300 2150);
FORCEPROP 2 LAST CDS_LIB logical_power
J 0
(4250 2125);
DISPLAY INVISIBLE (4250 2125);
FORCEADD Q_CAP..1
(2825 2500);
FORCEPROP 1 LAST VALUE 0.1UF
J 0
(2875 2550);
DISPLAY 0.510638 (2875 2550);
PAINT SKYBLUE (2875 2550);
FORCEPROP 1 LAST TOLERANCE 10%
J 0
(2875 2450);
DISPLAY 0.510638 (2875 2450);
PAINT SKYBLUE (2875 2450);
FORCEPROP 1 LAST MATERIAL X7R
J 0
(2875 2400);
DISPLAY 0.510638 (2875 2400);
PAINT SKYBLUE (2875 2400);
FORCEPROP 1 LAST PART_NUMBER CH4104K1B00
J 0
(2850 2275);
DISPLAY 0.510638 (2850 2275);
PAINT WHITE (2850 2275);
FORCEPROP 1 LAST VOLTAGE 25V
J 0
(2875 2500);
DISPLAY 0.510638 (2875 2500);
PAINT SKYBLUE (2875 2500);
FORCEPROP 1 LAST PACK_TYPE 0402
J 0
(2875 2350);
DISPLAY 0.510638 (2875 2350);
PAINT SKYBLUE (2875 2350);
FORCEPROP 1 LAST PATH I147
J 0
(2875 2650);
DISPLAY 0.978723 (2875 2650);
PAINT WHITE (2875 2650);
DISPLAY INVISIBLE (2875 2650);
FORCEPROP 2 LAST CDS_LIB pure_quanta
J 0
(2825 2500);
DISPLAY INVISIBLE (2825 2500);
FORCEPROP 1 LAST LOCATION C87
J 0
(2875 2600);
DISPLAY 0.702128 (2875 2600);
PAINT YELLOW (2875 2600);
FORCEPROP 1 LASTPIN (2825 2600) $PN 1
J 0
(2835 2580);
DISPLAY 0.808511 (2835 2580);
PAINT WHITE (2835 2580);
FORCEPROP 1 LASTPIN (2825 2400) $PN 2
J 0
(2835 2380);
DISPLAY 0.808511 (2835 2380);
PAINT WHITE (2835 2380);
FORCEPROP 2 LAST $SEC 1
J 0
(2875 2700);
DISPLAY 0.680851 (2875 2700);
PAINT MONO (2875 2700);
DISPLAY INVISIBLE (2875 2700);
FORCEPROP 0 LAST CDS_SEC 1
J 0
(2875 2700);
DISPLAY 0.680851 (2875 2700);
PAINT MONO (2875 2700);
DISPLAY INVISIBLE (2875 2700);
FORCEADD Q_CAP..1
(3025 2500);
FORCEPROP 1 LAST PACK_TYPE 0402
J 0
(3075 2350);
DISPLAY 0.510638 (3075 2350);
PAINT SKYBLUE (3075 2350);
FORCEPROP 1 LAST VALUE 0.1UF
J 0
(3075 2550);
DISPLAY 0.510638 (3075 2550);
PAINT SKYBLUE (3075 2550);
FORCEPROP 1 LAST TOLERANCE 10%
J 0
(3075 2450);
DISPLAY 0.510638 (3075 2450);
PAINT SKYBLUE (3075 2450);
FORCEPROP 1 LAST MATERIAL X7R
J 0
(3075 2400);
DISPLAY 0.510638 (3075 2400);
PAINT SKYBLUE (3075 2400);
FORCEPROP 1 LAST VOLTAGE 25V
J 0
(3075 2500);
DISPLAY 0.510638 (3075 2500);
PAINT SKYBLUE (3075 2500);
FORCEPROP 1 LAST PATH I148
J 0
(3075 2650);
DISPLAY 0.978723 (3075 2650);
PAINT WHITE (3075 2650);
DISPLAY INVISIBLE (3075 2650);
FORCEPROP 1 LAST PART_NUMBER CH4104K1B00
J 0
(3075 2350);
DISPLAY 0.510638 (3075 2350);
PAINT WHITE (3075 2350);
DISPLAY INVISIBLE (3075 2350);
FORCEPROP 2 LAST CDS_LIB pure_quanta
J 0
(3025 2500);
DISPLAY INVISIBLE (3025 2500);
FORCEPROP 1 LAST LOCATION C93
J 0
(3075 2600);
DISPLAY 0.702128 (3075 2600);
PAINT YELLOW (3075 2600);
FORCEPROP 1 LASTPIN (3025 2600) $PN 1
J 0
(3035 2580);
DISPLAY 0.808511 (3035 2580);
PAINT WHITE (3035 2580);
FORCEPROP 1 LASTPIN (3025 2400) $PN 2
J 0
(3035 2380);
DISPLAY 0.808511 (3035 2380);
PAINT WHITE (3035 2380);
FORCEPROP 2 LAST $SEC 1
J 0
(3075 2700);
DISPLAY 0.680851 (3075 2700);
PAINT MONO (3075 2700);
DISPLAY INVISIBLE (3075 2700);
FORCEPROP 0 LAST CDS_SEC 1
J 0
(3075 2700);
DISPLAY 0.680851 (3075 2700);
PAINT MONO (3075 2700);
DISPLAY INVISIBLE (3075 2700);
FORCEADD Q_CAP..1
(2825 3200);
FORCEPROP 1 LAST VALUE 0.1UF
J 0
(2875 3250);
DISPLAY 0.510638 (2875 3250);
PAINT SKYBLUE (2875 3250);
FORCEPROP 1 LAST TOLERANCE 10%
J 0
(2875 3150);
DISPLAY 0.510638 (2875 3150);
PAINT SKYBLUE (2875 3150);
FORCEPROP 1 LAST MATERIAL X7R
J 0
(2875 3100);
DISPLAY 0.510638 (2875 3100);
PAINT SKYBLUE (2875 3100);
FORCEPROP 1 LAST PART_NUMBER CH4104K1B00
J 0
(2825 2975);
DISPLAY 0.510638 (2825 2975);
PAINT WHITE (2825 2975);
FORCEPROP 1 LAST VOLTAGE 25V
J 0
(2875 3200);
DISPLAY 0.510638 (2875 3200);
PAINT SKYBLUE (2875 3200);
FORCEPROP 1 LAST PACK_TYPE 0402
J 0
(2875 3050);
DISPLAY 0.510638 (2875 3050);
PAINT SKYBLUE (2875 3050);
FORCEPROP 1 LAST PATH I149
J 0
(2875 3350);
DISPLAY 0.978723 (2875 3350);
PAINT WHITE (2875 3350);
DISPLAY INVISIBLE (2875 3350);
FORCEPROP 2 LAST CDS_LIB pure_quanta
J 0
(2825 3200);
DISPLAY INVISIBLE (2825 3200);
FORCEPROP 1 LAST LOCATION C86
J 0
(2875 3300);
DISPLAY 0.702128 (2875 3300);
PAINT YELLOW (2875 3300);
FORCEPROP 1 LASTPIN (2825 3300) $PN 1
J 0
(2835 3280);
DISPLAY 0.808511 (2835 3280);
PAINT WHITE (2835 3280);
FORCEPROP 1 LASTPIN (2825 3100) $PN 2
J 0
(2835 3080);
DISPLAY 0.808511 (2835 3080);
PAINT WHITE (2835 3080);
FORCEPROP 2 LAST $SEC 1
J 0
(2875 3400);
DISPLAY 0.680851 (2875 3400);
PAINT MONO (2875 3400);
DISPLAY INVISIBLE (2875 3400);
FORCEPROP 0 LAST CDS_SEC 1
J 0
(2875 3400);
DISPLAY 0.680851 (2875 3400);
PAINT MONO (2875 3400);
DISPLAY INVISIBLE (2875 3400);
FORCEADD Q_CAP..1
(3025 3200);
FORCEPROP 1 LAST TOLERANCE 10%
J 0
(3075 3150);
DISPLAY 0.510638 (3075 3150);
PAINT SKYBLUE (3075 3150);
FORCEPROP 1 LAST VOLTAGE 25V
J 0
(3075 3200);
DISPLAY 0.510638 (3075 3200);
PAINT SKYBLUE (3075 3200);
FORCEPROP 1 LAST MATERIAL X7R
J 0
(3075 3100);
DISPLAY 0.510638 (3075 3100);
PAINT SKYBLUE (3075 3100);
FORCEPROP 1 LAST PACK_TYPE 0402
J 0
(3075 3050);
DISPLAY 0.510638 (3075 3050);
PAINT SKYBLUE (3075 3050);
FORCEPROP 1 LAST VALUE 0.1UF
J 0
(3075 3250);
DISPLAY 0.510638 (3075 3250);
PAINT SKYBLUE (3075 3250);
FORCEPROP 1 LAST PATH I150
J 0
(3075 3350);
DISPLAY 0.978723 (3075 3350);
PAINT WHITE (3075 3350);
DISPLAY INVISIBLE (3075 3350);
FORCEPROP 1 LAST PART_NUMBER CH4104K1B00
J 0
(3075 3050);
DISPLAY 0.510638 (3075 3050);
PAINT WHITE (3075 3050);
DISPLAY INVISIBLE (3075 3050);
FORCEPROP 2 LAST CDS_LIB pure_quanta
J 0
(3025 3200);
DISPLAY INVISIBLE (3025 3200);
FORCEPROP 1 LAST LOCATION C92
J 0
(3075 3300);
DISPLAY 0.702128 (3075 3300);
PAINT YELLOW (3075 3300);
FORCEPROP 1 LASTPIN (3025 3300) $PN 1
J 0
(3035 3280);
DISPLAY 0.808511 (3035 3280);
PAINT WHITE (3035 3280);
FORCEPROP 1 LASTPIN (3025 3100) $PN 2
J 0
(3035 3080);
DISPLAY 0.808511 (3035 3080);
PAINT WHITE (3035 3080);
FORCEPROP 2 LAST $SEC 1
J 0
(3075 3400);
DISPLAY 0.680851 (3075 3400);
PAINT MONO (3075 3400);
DISPLAY INVISIBLE (3075 3400);
FORCEPROP 0 LAST CDS_SEC 1
J 0
(3075 3400);
DISPLAY 0.680851 (3075 3400);
PAINT MONO (3075 3400);
DISPLAY INVISIBLE (3075 3400);
FORCEADD Q_CAP..1
(2950 3825);
FORCEPROP 1 LAST VOLTAGE 25V
J 0
(3000 3825);
DISPLAY 0.510638 (3000 3825);
PAINT SKYBLUE (3000 3825);
FORCEPROP 1 LAST VALUE 0.1UF
J 0
(3000 3875);
DISPLAY 0.510638 (3000 3875);
PAINT SKYBLUE (3000 3875);
FORCEPROP 1 LAST PACK_TYPE 0402
J 0
(3000 3675);
DISPLAY 0.510638 (3000 3675);
PAINT SKYBLUE (3000 3675);
FORCEPROP 1 LAST TOLERANCE 10%
J 0
(3000 3775);
DISPLAY 0.510638 (3000 3775);
PAINT SKYBLUE (3000 3775);
FORCEPROP 1 LAST MATERIAL X7R
J 0
(3000 3725);
DISPLAY 0.510638 (3000 3725);
PAINT SKYBLUE (3000 3725);
FORCEPROP 1 LAST PATH I151
J 0
(3000 3975);
DISPLAY 0.978723 (3000 3975);
PAINT WHITE (3000 3975);
DISPLAY INVISIBLE (3000 3975);
FORCEPROP 1 LAST PART_NUMBER CH4104K1B00
J 0
(3000 3675);
DISPLAY 0.510638 (3000 3675);
PAINT WHITE (3000 3675);
DISPLAY INVISIBLE (3000 3675);
FORCEPROP 2 LAST CDS_LIB pure_quanta
J 0
(2950 3825);
DISPLAY INVISIBLE (2950 3825);
FORCEPROP 1 LAST LOCATION C91
J 0
(3000 3925);
DISPLAY 0.702128 (3000 3925);
PAINT YELLOW (3000 3925);
FORCEPROP 1 LASTPIN (2950 3925) $PN 1
J 0
(2960 3905);
DISPLAY 0.808511 (2960 3905);
PAINT WHITE (2960 3905);
FORCEPROP 1 LASTPIN (2950 3725) $PN 2
J 0
(2960 3705);
DISPLAY 0.808511 (2960 3705);
PAINT WHITE (2960 3705);
FORCEPROP 2 LAST $SEC 1
J 0
(3000 4025);
DISPLAY 0.680851 (3000 4025);
PAINT MONO (3000 4025);
DISPLAY INVISIBLE (3000 4025);
FORCEPROP 0 LAST CDS_SEC 1
J 0
(3000 4025);
DISPLAY 0.680851 (3000 4025);
PAINT MONO (3000 4025);
DISPLAY INVISIBLE (3000 4025);
FORCEADD Q_CAP..1
(3225 2500);
FORCEPROP 1 LAST VALUE 0.1UF
J 0
(3275 2550);
DISPLAY 0.510638 (3275 2550);
PAINT SKYBLUE (3275 2550);
FORCEPROP 1 LAST PACK_TYPE 0402
J 0
(3275 2350);
DISPLAY 0.510638 (3275 2350);
PAINT SKYBLUE (3275 2350);
FORCEPROP 1 LAST MATERIAL X7R
J 0
(3275 2400);
DISPLAY 0.510638 (3275 2400);
PAINT SKYBLUE (3275 2400);
FORCEPROP 1 LAST TOLERANCE 10%
J 0
(3275 2450);
DISPLAY 0.510638 (3275 2450);
PAINT SKYBLUE (3275 2450);
FORCEPROP 1 LAST VOLTAGE 25V
J 0
(3275 2500);
DISPLAY 0.510638 (3275 2500);
PAINT SKYBLUE (3275 2500);
FORCEPROP 1 LAST PATH I152
J 0
(3275 2650);
DISPLAY 0.978723 (3275 2650);
PAINT WHITE (3275 2650);
DISPLAY INVISIBLE (3275 2650);
FORCEPROP 1 LAST PART_NUMBER CH4104K1B00
J 0
(3275 2350);
DISPLAY 0.510638 (3275 2350);
PAINT WHITE (3275 2350);
DISPLAY INVISIBLE (3275 2350);
FORCEPROP 2 LAST CDS_LIB pure_quanta
J 0
(3225 2500);
DISPLAY INVISIBLE (3225 2500);
FORCEPROP 1 LAST LOCATION C100
J 0
(3275 2600);
DISPLAY 0.702128 (3275 2600);
PAINT YELLOW (3275 2600);
FORCEPROP 1 LASTPIN (3225 2600) $PN 1
J 0
(3235 2580);
DISPLAY 0.808511 (3235 2580);
PAINT WHITE (3235 2580);
FORCEPROP 1 LASTPIN (3225 2400) $PN 2
J 0
(3235 2380);
DISPLAY 0.808511 (3235 2380);
PAINT WHITE (3235 2380);
FORCEPROP 2 LAST $SEC 1
J 0
(3275 2700);
DISPLAY 0.680851 (3275 2700);
PAINT MONO (3275 2700);
DISPLAY INVISIBLE (3275 2700);
FORCEPROP 0 LAST CDS_SEC 1
J 0
(3275 2700);
DISPLAY 0.680851 (3275 2700);
PAINT MONO (3275 2700);
DISPLAY INVISIBLE (3275 2700);
FORCEADD Q_CAP..1
(3400 2500);
FORCEPROP 1 LAST PACK_TYPE 0402
J 0
(3450 2350);
DISPLAY 0.510638 (3450 2350);
PAINT SKYBLUE (3450 2350);
FORCEPROP 1 LAST VALUE 0.1UF
J 0
(3450 2550);
DISPLAY 0.510638 (3450 2550);
PAINT SKYBLUE (3450 2550);
FORCEPROP 1 LAST TOLERANCE 10%
J 0
(3450 2450);
DISPLAY 0.510638 (3450 2450);
PAINT SKYBLUE (3450 2450);
FORCEPROP 1 LAST MATERIAL X7R
J 0
(3450 2400);
DISPLAY 0.510638 (3450 2400);
PAINT SKYBLUE (3450 2400);
FORCEPROP 1 LAST VOLTAGE 25V
J 0
(3450 2500);
DISPLAY 0.510638 (3450 2500);
PAINT SKYBLUE (3450 2500);
FORCEPROP 1 LAST PATH I153
J 0
(3450 2650);
DISPLAY 0.978723 (3450 2650);
PAINT WHITE (3450 2650);
DISPLAY INVISIBLE (3450 2650);
FORCEPROP 1 LAST PART_NUMBER CH4104K1B00
J 0
(3450 2350);
DISPLAY 0.510638 (3450 2350);
PAINT WHITE (3450 2350);
DISPLAY INVISIBLE (3450 2350);
FORCEPROP 2 LAST CDS_LIB pure_quanta
J 0
(3400 2500);
DISPLAY INVISIBLE (3400 2500);
FORCEPROP 1 LAST LOCATION C105
J 0
(3450 2600);
DISPLAY 0.702128 (3450 2600);
PAINT YELLOW (3450 2600);
FORCEPROP 1 LASTPIN (3400 2600) $PN 1
J 0
(3410 2580);
DISPLAY 0.808511 (3410 2580);
PAINT WHITE (3410 2580);
FORCEPROP 1 LASTPIN (3400 2400) $PN 2
J 0
(3410 2380);
DISPLAY 0.808511 (3410 2380);
PAINT WHITE (3410 2380);
FORCEPROP 2 LAST $SEC 1
J 0
(3450 2700);
DISPLAY 0.680851 (3450 2700);
PAINT MONO (3450 2700);
DISPLAY INVISIBLE (3450 2700);
FORCEPROP 0 LAST CDS_SEC 1
J 0
(3450 2700);
DISPLAY 0.680851 (3450 2700);
PAINT MONO (3450 2700);
DISPLAY INVISIBLE (3450 2700);
FORCEADD Q_CAP..1
(3225 3200);
FORCEPROP 1 LAST VALUE 0.1UF
J 0
(3275 3250);
DISPLAY 0.510638 (3275 3250);
PAINT SKYBLUE (3275 3250);
FORCEPROP 1 LAST TOLERANCE 10%
J 0
(3275 3150);
DISPLAY 0.510638 (3275 3150);
PAINT SKYBLUE (3275 3150);
FORCEPROP 1 LAST VOLTAGE 25V
J 0
(3275 3200);
DISPLAY 0.510638 (3275 3200);
PAINT SKYBLUE (3275 3200);
FORCEPROP 1 LAST MATERIAL X7R
J 0
(3275 3100);
DISPLAY 0.510638 (3275 3100);
PAINT SKYBLUE (3275 3100);
FORCEPROP 1 LAST PACK_TYPE 0402
J 0
(3275 3050);
DISPLAY 0.510638 (3275 3050);
PAINT SKYBLUE (3275 3050);
FORCEPROP 1 LAST PATH I154
J 0
(3275 3350);
DISPLAY 0.978723 (3275 3350);
PAINT WHITE (3275 3350);
DISPLAY INVISIBLE (3275 3350);
FORCEPROP 1 LAST PART_NUMBER CH4104K1B00
J 0
(3275 3050);
DISPLAY 0.510638 (3275 3050);
PAINT WHITE (3275 3050);
DISPLAY INVISIBLE (3275 3050);
FORCEPROP 2 LAST CDS_LIB pure_quanta
J 0
(3225 3200);
DISPLAY INVISIBLE (3225 3200);
FORCEPROP 1 LAST LOCATION C99
J 0
(3275 3300);
DISPLAY 0.702128 (3275 3300);
PAINT YELLOW (3275 3300);
FORCEPROP 1 LASTPIN (3225 3300) $PN 1
J 0
(3235 3280);
DISPLAY 0.808511 (3235 3280);
PAINT WHITE (3235 3280);
FORCEPROP 1 LASTPIN (3225 3100) $PN 2
J 0
(3235 3080);
DISPLAY 0.808511 (3235 3080);
PAINT WHITE (3235 3080);
FORCEPROP 2 LAST $SEC 1
J 0
(3275 3400);
DISPLAY 0.680851 (3275 3400);
PAINT MONO (3275 3400);
DISPLAY INVISIBLE (3275 3400);
FORCEPROP 0 LAST CDS_SEC 1
J 0
(3275 3400);
DISPLAY 0.680851 (3275 3400);
PAINT MONO (3275 3400);
DISPLAY INVISIBLE (3275 3400);
FORCEADD Q_CAP..1
(3400 3200);
FORCEPROP 1 LAST PACK_TYPE C0402
J 0
(3425 3050);
DISPLAY 0.510638 (3425 3050);
PAINT SKYBLUE (3425 3050);
FORCEPROP 1 LAST MATERIAL X6S
J 0
(3450 3100);
DISPLAY 0.510638 (3450 3100);
PAINT SKYBLUE (3450 3100);
FORCEPROP 1 LAST VALUE 1UF
J 0
(3450 3250);
DISPLAY 0.510638 (3450 3250);
PAINT SKYBLUE (3450 3250);
FORCEPROP 1 LAST VOLTAGE 25V
J 0
(3450 3200);
DISPLAY 0.510638 (3450 3200);
PAINT SKYBLUE (3450 3200);
FORCEPROP 1 LAST TOLERANCE 10%
J 0
(3450 3150);
DISPLAY 0.510638 (3450 3150);
PAINT SKYBLUE (3450 3150);
FORCEPROP 1 LAST PART_NUMBER CH5104KEB02
J 0
(3475 2975);
DISPLAY 0.510638 (3475 2975);
PAINT WHITE (3475 2975);
FORCEPROP 1 LAST PATH I155
J 0
(3450 3350);
DISPLAY 0.978723 (3450 3350);
PAINT WHITE (3450 3350);
DISPLAY INVISIBLE (3450 3350);
FORCEPROP 2 LAST CDS_LIB pure_quanta
J 0
(3400 3200);
DISPLAY INVISIBLE (3400 3200);
FORCEPROP 1 LAST LOCATION C104
J 0
(3450 3300);
DISPLAY 0.702128 (3450 3300);
PAINT YELLOW (3450 3300);
FORCEPROP 1 LASTPIN (3400 3300) $PN 1
J 0
(3410 3280);
DISPLAY 0.808511 (3410 3280);
PAINT WHITE (3410 3280);
FORCEPROP 1 LASTPIN (3400 3100) $PN 2
J 0
(3410 3080);
DISPLAY 0.808511 (3410 3080);
PAINT WHITE (3410 3080);
FORCEPROP 2 LAST $SEC 1
J 0
(3450 3400);
DISPLAY 0.680851 (3450 3400);
PAINT MONO (3450 3400);
DISPLAY INVISIBLE (3450 3400);
FORCEPROP 0 LAST CDS_SEC 1
J 0
(3450 3400);
DISPLAY 0.680851 (3450 3400);
PAINT MONO (3450 3400);
DISPLAY INVISIBLE (3450 3400);
FORCEADD Q_CAP..1
(3575 2500);
FORCEPROP 1 LAST PACK_TYPE 0402
J 0
(3625 2350);
DISPLAY 0.510638 (3625 2350);
PAINT SKYBLUE (3625 2350);
FORCEPROP 1 LAST TOLERANCE 10%
J 0
(3625 2450);
DISPLAY 0.510638 (3625 2450);
PAINT SKYBLUE (3625 2450);
FORCEPROP 1 LAST MATERIAL X7R
J 0
(3625 2400);
DISPLAY 0.510638 (3625 2400);
PAINT SKYBLUE (3625 2400);
FORCEPROP 1 LAST VOLTAGE 25V
J 0
(3625 2500);
DISPLAY 0.510638 (3625 2500);
PAINT SKYBLUE (3625 2500);
FORCEPROP 1 LAST VALUE 0.1UF
J 0
(3625 2550);
DISPLAY 0.510638 (3625 2550);
PAINT SKYBLUE (3625 2550);
FORCEPROP 1 LAST PATH I156
J 0
(3625 2650);
DISPLAY 0.978723 (3625 2650);
PAINT WHITE (3625 2650);
DISPLAY INVISIBLE (3625 2650);
FORCEPROP 1 LAST PART_NUMBER CH4104K1B00
J 0
(3625 2350);
DISPLAY 0.510638 (3625 2350);
PAINT WHITE (3625 2350);
DISPLAY INVISIBLE (3625 2350);
FORCEPROP 2 LAST CDS_LIB pure_quanta
J 0
(3575 2500);
DISPLAY INVISIBLE (3575 2500);
FORCEPROP 1 LAST LOCATION C109
J 0
(3625 2600);
DISPLAY 0.702128 (3625 2600);
PAINT YELLOW (3625 2600);
FORCEPROP 1 LASTPIN (3575 2600) $PN 1
J 0
(3585 2580);
DISPLAY 0.808511 (3585 2580);
PAINT WHITE (3585 2580);
FORCEPROP 1 LASTPIN (3575 2400) $PN 2
J 0
(3585 2380);
DISPLAY 0.808511 (3585 2380);
PAINT WHITE (3585 2380);
FORCEPROP 2 LAST $SEC 1
J 0
(3625 2700);
DISPLAY 0.680851 (3625 2700);
PAINT MONO (3625 2700);
DISPLAY INVISIBLE (3625 2700);
FORCEPROP 0 LAST CDS_SEC 1
J 0
(3625 2700);
DISPLAY 0.680851 (3625 2700);
PAINT MONO (3625 2700);
DISPLAY INVISIBLE (3625 2700);
FORCEADD Q_CAP..1
(3575 3200);
FORCEPROP 1 LAST MATERIAL X6S
J 0
(3625 3100);
DISPLAY 0.510638 (3625 3100);
PAINT SKYBLUE (3625 3100);
FORCEPROP 1 LAST VALUE 1UF
J 0
(3625 3250);
DISPLAY 0.510638 (3625 3250);
PAINT SKYBLUE (3625 3250);
FORCEPROP 1 LAST TOLERANCE 10%
J 0
(3625 3150);
DISPLAY 0.510638 (3625 3150);
PAINT SKYBLUE (3625 3150);
FORCEPROP 1 LAST VOLTAGE 25V
J 0
(3625 3200);
DISPLAY 0.510638 (3625 3200);
PAINT SKYBLUE (3625 3200);
FORCEPROP 1 LAST PACK_TYPE C0402
J 0
(3600 3050);
DISPLAY 0.510638 (3600 3050);
PAINT SKYBLUE (3600 3050);
FORCEPROP 1 LAST PATH I157
J 0
(3625 3350);
DISPLAY 0.978723 (3625 3350);
PAINT WHITE (3625 3350);
DISPLAY INVISIBLE (3625 3350);
FORCEPROP 1 LAST PART_NUMBER CH5104KEB02
J 0
(3625 3050);
DISPLAY 0.510638 (3625 3050);
PAINT WHITE (3625 3050);
DISPLAY INVISIBLE (3625 3050);
FORCEPROP 2 LAST CDS_LIB pure_quanta
J 0
(3575 3200);
DISPLAY INVISIBLE (3575 3200);
FORCEPROP 1 LAST LOCATION C108
J 0
(3625 3300);
DISPLAY 0.702128 (3625 3300);
PAINT YELLOW (3625 3300);
FORCEPROP 1 LASTPIN (3575 3300) $PN 1
J 0
(3585 3280);
DISPLAY 0.808511 (3585 3280);
PAINT WHITE (3585 3280);
FORCEPROP 1 LASTPIN (3575 3100) $PN 2
J 0
(3585 3080);
DISPLAY 0.808511 (3585 3080);
PAINT WHITE (3585 3080);
FORCEPROP 2 LAST $SEC 1
J 0
(3625 3400);
DISPLAY 0.680851 (3625 3400);
PAINT MONO (3625 3400);
DISPLAY INVISIBLE (3625 3400);
FORCEPROP 0 LAST CDS_SEC 1
J 0
(3625 3400);
DISPLAY 0.680851 (3625 3400);
PAINT MONO (3625 3400);
DISPLAY INVISIBLE (3625 3400);
FORCEADD Q_CAP..1
(3750 2500);
FORCEPROP 1 LAST PACK_TYPE C0402
J 0
(3775 2350);
DISPLAY 0.510638 (3775 2350);
PAINT SKYBLUE (3775 2350);
FORCEPROP 1 LAST TOLERANCE 10%
J 0
(3800 2450);
DISPLAY 0.510638 (3800 2450);
PAINT SKYBLUE (3800 2450);
FORCEPROP 1 LAST MATERIAL X6S
J 0
(3800 2400);
DISPLAY 0.510638 (3800 2400);
PAINT SKYBLUE (3800 2400);
FORCEPROP 1 LAST PART_NUMBER CH5104KEB02
J 0
(3575 2275);
DISPLAY 0.510638 (3575 2275);
PAINT WHITE (3575 2275);
FORCEPROP 1 LAST VOLTAGE 25V
J 0
(3800 2500);
DISPLAY 0.510638 (3800 2500);
PAINT SKYBLUE (3800 2500);
FORCEPROP 1 LAST VALUE 1UF
J 0
(3800 2550);
DISPLAY 0.510638 (3800 2550);
PAINT SKYBLUE (3800 2550);
FORCEPROP 1 LAST PATH I158
J 0
(3800 2650);
DISPLAY 0.978723 (3800 2650);
PAINT WHITE (3800 2650);
DISPLAY INVISIBLE (3800 2650);
FORCEPROP 2 LAST CDS_LIB pure_quanta
J 0
(3750 2500);
DISPLAY INVISIBLE (3750 2500);
FORCEPROP 1 LAST LOCATION C114
J 0
(3800 2600);
DISPLAY 0.702128 (3800 2600);
PAINT YELLOW (3800 2600);
FORCEPROP 1 LASTPIN (3750 2600) $PN 1
J 0
(3760 2580);
DISPLAY 0.808511 (3760 2580);
PAINT WHITE (3760 2580);
FORCEPROP 1 LASTPIN (3750 2400) $PN 2
J 0
(3760 2380);
DISPLAY 0.808511 (3760 2380);
PAINT WHITE (3760 2380);
FORCEPROP 2 LAST $SEC 1
J 0
(3800 2700);
DISPLAY 0.680851 (3800 2700);
PAINT MONO (3800 2700);
DISPLAY INVISIBLE (3800 2700);
FORCEPROP 0 LAST CDS_SEC 1
J 0
(3800 2700);
DISPLAY 0.680851 (3800 2700);
PAINT MONO (3800 2700);
DISPLAY INVISIBLE (3800 2700);
FORCEADD Q_CAP..1
(3950 2500);
FORCEPROP 1 LAST VALUE 1UF
J 0
(4000 2550);
DISPLAY 0.510638 (4000 2550);
PAINT SKYBLUE (4000 2550);
FORCEPROP 1 LAST VOLTAGE 25V
J 0
(4000 2500);
DISPLAY 0.510638 (4000 2500);
PAINT SKYBLUE (4000 2500);
FORCEPROP 1 LAST MATERIAL X6S
J 0
(4000 2400);
DISPLAY 0.510638 (4000 2400);
PAINT SKYBLUE (4000 2400);
FORCEPROP 1 LAST TOLERANCE 10%
J 0
(4000 2450);
DISPLAY 0.510638 (4000 2450);
PAINT SKYBLUE (4000 2450);
FORCEPROP 1 LAST PACK_TYPE C0402
J 0
(3975 2350);
DISPLAY 0.510638 (3975 2350);
PAINT SKYBLUE (3975 2350);
FORCEPROP 1 LAST PATH I159
J 0
(4000 2650);
DISPLAY 0.978723 (4000 2650);
PAINT WHITE (4000 2650);
DISPLAY INVISIBLE (4000 2650);
FORCEPROP 1 LAST PART_NUMBER CH5104KEB02
J 0
(4000 2350);
DISPLAY 0.510638 (4000 2350);
PAINT WHITE (4000 2350);
DISPLAY INVISIBLE (4000 2350);
FORCEPROP 2 LAST CDS_LIB pure_quanta
J 0
(3950 2500);
DISPLAY INVISIBLE (3950 2500);
FORCEPROP 1 LAST LOCATION C119
J 0
(4000 2600);
DISPLAY 0.702128 (4000 2600);
PAINT YELLOW (4000 2600);
FORCEPROP 1 LASTPIN (3950 2600) $PN 1
J 0
(3960 2580);
DISPLAY 0.808511 (3960 2580);
PAINT WHITE (3960 2580);
FORCEPROP 1 LASTPIN (3950 2400) $PN 2
J 0
(3960 2380);
DISPLAY 0.808511 (3960 2380);
PAINT WHITE (3960 2380);
FORCEPROP 2 LAST $SEC 1
J 0
(4000 2700);
DISPLAY 0.680851 (4000 2700);
PAINT MONO (4000 2700);
DISPLAY INVISIBLE (4000 2700);
FORCEPROP 0 LAST CDS_SEC 1
J 0
(4000 2700);
DISPLAY 0.680851 (4000 2700);
PAINT MONO (4000 2700);
DISPLAY INVISIBLE (4000 2700);
FORCEADD UNIVERSAL_GND..1
(4050 2925);
FORCEPROP 3 LASTPIN (4050 2975) SIG_NAME GND\g
J 0
(4060 2985);
DISPLAY 0.659574 (4060 2985);
PAINT MONO (4060 2985);
DISPLAY INVISIBLE (4060 2985);
FORCEPROP 1 LAST PATH I161
J 0
(4125 2925);
DISPLAY 0.872340 (4125 2925);
PAINT AQUA (4125 2925);
DISPLAY INVISIBLE (4125 2925);
FORCEPROP 1 LAST HDL_POWER GND
J 1
(4075 2850);
DISPLAY 0.702128 (4075 2850);
PAINT GREEN (4075 2850);
DISPLAY INVISIBLE (4075 2850);
FORCEPROP 2 LAST CDS_LIB logical_power
J 0
(4050 2925);
DISPLAY INVISIBLE (4050 2925);
FORCEADD Q_CAP..1
(3950 3200);
FORCEPROP 1 LAST MATERIAL X6S
J 0
(4000 3100);
DISPLAY 0.510638 (4000 3100);
PAINT SKYBLUE (4000 3100);
FORCEPROP 1 LAST VALUE 22UF
J 0
(4000 3250);
DISPLAY 0.510638 (4000 3250);
PAINT SKYBLUE (4000 3250);
FORCEPROP 1 LAST PACK_TYPE C0603
J 0
(4000 3050);
DISPLAY 0.510638 (4000 3050);
PAINT SKYBLUE (4000 3050);
FORCEPROP 1 LAST TOLERANCE 20%
J 0
(4000 3150);
DISPLAY 0.510638 (4000 3150);
PAINT SKYBLUE (4000 3150);
FORCEPROP 1 LAST VOLTAGE 6.3V
J 0
(4000 3200);
DISPLAY 0.510638 (4000 3200);
PAINT SKYBLUE (4000 3200);
FORCEPROP 2 LAST CDS_LIB pure_quanta
J 0
(3950 3200);
DISPLAY INVISIBLE (3950 3200);
FORCEPROP 1 LAST PATH I162
J 0
(4000 3350);
DISPLAY 0.978723 (4000 3350);
PAINT WHITE (4000 3350);
DISPLAY INVISIBLE (4000 3350);
FORCEPROP 1 LAST PART_NUMBER CH6221ME900
J 0
(4000 3050);
DISPLAY 0.510638 (4000 3050);
PAINT WHITE (4000 3050);
DISPLAY INVISIBLE (4000 3050);
FORCEPROP 1 LAST LOCATION C118
J 0
(4000 3300);
DISPLAY 0.702128 (4000 3300);
PAINT YELLOW (4000 3300);
FORCEPROP 1 LASTPIN (3950 3300) $PN 1
J 0
(3960 3280);
DISPLAY 0.808511 (3960 3280);
PAINT WHITE (3960 3280);
FORCEPROP 1 LASTPIN (3950 3100) $PN 2
J 0
(3960 3080);
DISPLAY 0.808511 (3960 3080);
PAINT WHITE (3960 3080);
FORCEPROP 0 LAST $SEC 1
J 0
(4000 3350);
DISPLAY 0.680851 (4000 3350);
PAINT MONO (4000 3350);
DISPLAY INVISIBLE (4000 3350);
FORCEPROP 0 LAST CDS_SEC 1
J 0
(4000 3350);
DISPLAY 0.680851 (4000 3350);
DISPLAY INVISIBLE (4000 3350);
FORCEADD Q_CAP..1
(3150 3825);
FORCEPROP 1 LAST PACK_TYPE 0402
J 0
(3200 3675);
DISPLAY 0.510638 (3200 3675);
PAINT SKYBLUE (3200 3675);
FORCEPROP 1 LAST MATERIAL X7R
J 0
(3200 3725);
DISPLAY 0.510638 (3200 3725);
PAINT SKYBLUE (3200 3725);
FORCEPROP 1 LAST TOLERANCE 10%
J 0
(3200 3775);
DISPLAY 0.510638 (3200 3775);
PAINT SKYBLUE (3200 3775);
FORCEPROP 1 LAST VOLTAGE 25V
J 0
(3200 3825);
DISPLAY 0.510638 (3200 3825);
PAINT SKYBLUE (3200 3825);
FORCEPROP 1 LAST VALUE 0.1UF
J 0
(3200 3875);
DISPLAY 0.510638 (3200 3875);
PAINT SKYBLUE (3200 3875);
FORCEPROP 1 LAST PATH I163
J 0
(3200 3975);
DISPLAY 0.978723 (3200 3975);
PAINT WHITE (3200 3975);
DISPLAY INVISIBLE (3200 3975);
FORCEPROP 1 LAST PART_NUMBER CH4104K1B00
J 0
(3200 3675);
DISPLAY 0.510638 (3200 3675);
PAINT WHITE (3200 3675);
DISPLAY INVISIBLE (3200 3675);
FORCEPROP 2 LAST CDS_LIB pure_quanta
J 0
(3150 3825);
DISPLAY INVISIBLE (3150 3825);
FORCEPROP 1 LAST LOCATION C98
J 0
(3200 3925);
DISPLAY 0.702128 (3200 3925);
PAINT YELLOW (3200 3925);
FORCEPROP 1 LASTPIN (3150 3925) $PN 1
J 0
(3160 3905);
DISPLAY 0.808511 (3160 3905);
PAINT WHITE (3160 3905);
FORCEPROP 1 LASTPIN (3150 3725) $PN 2
J 0
(3160 3705);
DISPLAY 0.808511 (3160 3705);
PAINT WHITE (3160 3705);
FORCEPROP 2 LAST $SEC 1
J 0
(3200 4025);
DISPLAY 0.680851 (3200 4025);
PAINT MONO (3200 4025);
DISPLAY INVISIBLE (3200 4025);
FORCEPROP 0 LAST CDS_SEC 1
J 0
(3200 4025);
DISPLAY 0.680851 (3200 4025);
PAINT MONO (3200 4025);
DISPLAY INVISIBLE (3200 4025);
FORCEADD Q_CAP..1
(3325 3825);
FORCEPROP 1 LAST VOLTAGE 25V
J 0
(3375 3825);
DISPLAY 0.510638 (3375 3825);
PAINT SKYBLUE (3375 3825);
FORCEPROP 1 LAST VALUE 0.1UF
J 0
(3375 3875);
DISPLAY 0.510638 (3375 3875);
PAINT SKYBLUE (3375 3875);
FORCEPROP 1 LAST PACK_TYPE 0402
J 0
(3375 3675);
DISPLAY 0.510638 (3375 3675);
PAINT SKYBLUE (3375 3675);
FORCEPROP 1 LAST TOLERANCE 10%
J 0
(3375 3775);
DISPLAY 0.510638 (3375 3775);
PAINT SKYBLUE (3375 3775);
FORCEPROP 1 LAST MATERIAL X7R
J 0
(3375 3725);
DISPLAY 0.510638 (3375 3725);
PAINT SKYBLUE (3375 3725);
FORCEPROP 1 LAST PATH I164
J 0
(3375 3975);
DISPLAY 0.978723 (3375 3975);
PAINT WHITE (3375 3975);
DISPLAY INVISIBLE (3375 3975);
FORCEPROP 1 LAST PART_NUMBER CH4104K1B00
J 0
(3375 3675);
DISPLAY 0.510638 (3375 3675);
PAINT WHITE (3375 3675);
DISPLAY INVISIBLE (3375 3675);
FORCEPROP 2 LAST CDS_LIB pure_quanta
J 0
(3325 3825);
DISPLAY INVISIBLE (3325 3825);
FORCEPROP 1 LAST LOCATION C103
J 0
(3375 3925);
DISPLAY 0.702128 (3375 3925);
PAINT YELLOW (3375 3925);
FORCEPROP 1 LASTPIN (3325 3925) $PN 1
J 0
(3335 3905);
DISPLAY 0.808511 (3335 3905);
PAINT WHITE (3335 3905);
FORCEPROP 1 LASTPIN (3325 3725) $PN 2
J 0
(3335 3705);
DISPLAY 0.808511 (3335 3705);
PAINT WHITE (3335 3705);
FORCEPROP 2 LAST $SEC 1
J 0
(3375 4025);
DISPLAY 0.680851 (3375 4025);
PAINT MONO (3375 4025);
DISPLAY INVISIBLE (3375 4025);
FORCEPROP 0 LAST CDS_SEC 1
J 0
(3375 4025);
DISPLAY 0.680851 (3375 4025);
PAINT MONO (3375 4025);
DISPLAY INVISIBLE (3375 4025);
FORCEADD Q_CAP..1
(3525 3825);
FORCEPROP 1 LAST VOLTAGE 25V
J 0
(3575 3825);
DISPLAY 0.510638 (3575 3825);
PAINT SKYBLUE (3575 3825);
FORCEPROP 1 LAST VALUE 0.1UF
J 0
(3575 3875);
DISPLAY 0.510638 (3575 3875);
PAINT SKYBLUE (3575 3875);
FORCEPROP 1 LAST TOLERANCE 10%
J 0
(3575 3775);
DISPLAY 0.510638 (3575 3775);
PAINT SKYBLUE (3575 3775);
FORCEPROP 1 LAST MATERIAL X7R
J 0
(3575 3725);
DISPLAY 0.510638 (3575 3725);
PAINT SKYBLUE (3575 3725);
FORCEPROP 1 LAST PACK_TYPE 0402
J 0
(3575 3675);
DISPLAY 0.510638 (3575 3675);
PAINT SKYBLUE (3575 3675);
FORCEPROP 1 LAST PATH I165
J 0
(3575 3975);
DISPLAY 0.978723 (3575 3975);
PAINT WHITE (3575 3975);
DISPLAY INVISIBLE (3575 3975);
FORCEPROP 1 LAST PART_NUMBER CH4104K1B00
J 0
(3575 3675);
DISPLAY 0.510638 (3575 3675);
PAINT WHITE (3575 3675);
DISPLAY INVISIBLE (3575 3675);
FORCEPROP 2 LAST CDS_LIB pure_quanta
J 0
(3525 3825);
DISPLAY INVISIBLE (3525 3825);
FORCEPROP 1 LAST LOCATION C107
J 0
(3575 3925);
DISPLAY 0.702128 (3575 3925);
PAINT YELLOW (3575 3925);
FORCEPROP 1 LASTPIN (3525 3925) $PN 1
J 0
(3535 3905);
DISPLAY 0.808511 (3535 3905);
PAINT WHITE (3535 3905);
FORCEPROP 1 LASTPIN (3525 3725) $PN 2
J 0
(3535 3705);
DISPLAY 0.808511 (3535 3705);
PAINT WHITE (3535 3705);
FORCEPROP 2 LAST $SEC 1
J 0
(3575 4025);
DISPLAY 0.680851 (3575 4025);
PAINT MONO (3575 4025);
DISPLAY INVISIBLE (3575 4025);
FORCEPROP 0 LAST CDS_SEC 1
J 0
(3575 4025);
DISPLAY 0.680851 (3575 4025);
PAINT MONO (3575 4025);
DISPLAY INVISIBLE (3575 4025);
FORCEADD Q_CAP..1
(3725 3825);
FORCEPROP 1 LAST VALUE 0.1UF
J 0
(3775 3875);
DISPLAY 0.510638 (3775 3875);
PAINT SKYBLUE (3775 3875);
FORCEPROP 1 LAST TOLERANCE 10%
J 0
(3775 3775);
DISPLAY 0.510638 (3775 3775);
PAINT SKYBLUE (3775 3775);
FORCEPROP 1 LAST VOLTAGE 25V
J 0
(3775 3825);
DISPLAY 0.510638 (3775 3825);
PAINT SKYBLUE (3775 3825);
FORCEPROP 1 LAST PACK_TYPE 0402
J 0
(3775 3675);
DISPLAY 0.510638 (3775 3675);
PAINT SKYBLUE (3775 3675);
FORCEPROP 1 LAST MATERIAL X7R
J 0
(3775 3725);
DISPLAY 0.510638 (3775 3725);
PAINT SKYBLUE (3775 3725);
FORCEPROP 1 LAST PATH I166
J 0
(3775 3975);
DISPLAY 0.978723 (3775 3975);
PAINT WHITE (3775 3975);
DISPLAY INVISIBLE (3775 3975);
FORCEPROP 1 LAST PART_NUMBER CH4104K1B00
J 0
(3775 3675);
DISPLAY 0.510638 (3775 3675);
PAINT WHITE (3775 3675);
DISPLAY INVISIBLE (3775 3675);
FORCEPROP 2 LAST CDS_LIB pure_quanta
J 0
(3725 3825);
DISPLAY INVISIBLE (3725 3825);
FORCEPROP 1 LAST LOCATION C112
J 0
(3775 3925);
DISPLAY 0.702128 (3775 3925);
PAINT YELLOW (3775 3925);
FORCEPROP 1 LASTPIN (3725 3925) $PN 1
J 0
(3735 3905);
DISPLAY 0.808511 (3735 3905);
PAINT WHITE (3735 3905);
FORCEPROP 1 LASTPIN (3725 3725) $PN 2
J 0
(3735 3705);
DISPLAY 0.808511 (3735 3705);
PAINT WHITE (3735 3705);
FORCEPROP 2 LAST $SEC 1
J 0
(3775 4025);
DISPLAY 0.680851 (3775 4025);
PAINT MONO (3775 4025);
DISPLAY INVISIBLE (3775 4025);
FORCEPROP 0 LAST CDS_SEC 1
J 0
(3775 4025);
DISPLAY 0.680851 (3775 4025);
PAINT MONO (3775 4025);
DISPLAY INVISIBLE (3775 4025);
FORCEADD Q_CAP..1
(3900 3825);
FORCEPROP 1 LAST PART_NUMBER CH5104KEB02
J 0
(3925 3600);
DISPLAY 0.510638 (3925 3600);
PAINT WHITE (3925 3600);
FORCEPROP 1 LAST PACK_TYPE C0402
J 0
(3925 3675);
DISPLAY 0.510638 (3925 3675);
PAINT SKYBLUE (3925 3675);
FORCEPROP 1 LAST MATERIAL X6S
J 0
(3950 3725);
DISPLAY 0.510638 (3950 3725);
PAINT SKYBLUE (3950 3725);
FORCEPROP 1 LAST VALUE 1UF
J 0
(3950 3875);
DISPLAY 0.510638 (3950 3875);
PAINT SKYBLUE (3950 3875);
FORCEPROP 1 LAST VOLTAGE 25V
J 0
(3950 3825);
DISPLAY 0.510638 (3950 3825);
PAINT SKYBLUE (3950 3825);
FORCEPROP 1 LAST TOLERANCE 10%
J 0
(3950 3775);
DISPLAY 0.510638 (3950 3775);
PAINT SKYBLUE (3950 3775);
FORCEPROP 1 LAST PATH I167
J 0
(3950 3975);
DISPLAY 0.978723 (3950 3975);
PAINT WHITE (3950 3975);
DISPLAY INVISIBLE (3950 3975);
FORCEPROP 2 LAST CDS_LIB pure_quanta
J 0
(3900 3825);
DISPLAY INVISIBLE (3900 3825);
FORCEPROP 1 LAST LOCATION C117
J 0
(3950 3925);
DISPLAY 0.702128 (3950 3925);
PAINT YELLOW (3950 3925);
FORCEPROP 1 LASTPIN (3900 3925) $PN 1
J 0
(3910 3905);
DISPLAY 0.808511 (3910 3905);
PAINT WHITE (3910 3905);
FORCEPROP 1 LASTPIN (3900 3725) $PN 2
J 0
(3910 3705);
DISPLAY 0.808511 (3910 3705);
PAINT WHITE (3910 3705);
FORCEPROP 2 LAST $SEC 1
J 0
(3950 4025);
DISPLAY 0.680851 (3950 4025);
PAINT MONO (3950 4025);
DISPLAY INVISIBLE (3950 4025);
FORCEPROP 0 LAST CDS_SEC 1
J 0
(3950 4025);
DISPLAY 0.680851 (3950 4025);
PAINT MONO (3950 4025);
DISPLAY INVISIBLE (3950 4025);
FORCEADD Q_CAP..1
(4075 3825);
FORCEPROP 1 LAST PACK_TYPE C0402
J 0
(4100 3675);
DISPLAY 0.510638 (4100 3675);
PAINT SKYBLUE (4100 3675);
FORCEPROP 1 LAST MATERIAL X6S
J 0
(4125 3725);
DISPLAY 0.510638 (4125 3725);
PAINT SKYBLUE (4125 3725);
FORCEPROP 1 LAST VALUE 1UF
J 0
(4125 3875);
DISPLAY 0.510638 (4125 3875);
PAINT SKYBLUE (4125 3875);
FORCEPROP 1 LAST VOLTAGE 25V
J 0
(4125 3825);
DISPLAY 0.510638 (4125 3825);
PAINT SKYBLUE (4125 3825);
FORCEPROP 1 LAST TOLERANCE 10%
J 0
(4125 3775);
DISPLAY 0.510638 (4125 3775);
PAINT SKYBLUE (4125 3775);
FORCEPROP 1 LAST PATH I168
J 0
(4125 3975);
DISPLAY 0.978723 (4125 3975);
PAINT WHITE (4125 3975);
DISPLAY INVISIBLE (4125 3975);
FORCEPROP 1 LAST PART_NUMBER CH5104KEB02
J 0
(4125 3675);
DISPLAY 0.510638 (4125 3675);
PAINT WHITE (4125 3675);
DISPLAY INVISIBLE (4125 3675);
FORCEPROP 2 LAST CDS_LIB pure_quanta
J 0
(4075 3825);
DISPLAY INVISIBLE (4075 3825);
FORCEPROP 1 LAST LOCATION C122
J 0
(4125 3925);
DISPLAY 0.702128 (4125 3925);
PAINT YELLOW (4125 3925);
FORCEPROP 1 LASTPIN (4075 3925) $PN 1
J 0
(4085 3905);
DISPLAY 0.808511 (4085 3905);
PAINT WHITE (4085 3905);
FORCEPROP 1 LASTPIN (4075 3725) $PN 2
J 0
(4085 3705);
DISPLAY 0.808511 (4085 3705);
PAINT WHITE (4085 3705);
FORCEPROP 2 LAST $SEC 1
J 0
(4125 4025);
DISPLAY 0.680851 (4125 4025);
PAINT MONO (4125 4025);
DISPLAY INVISIBLE (4125 4025);
FORCEPROP 0 LAST CDS_SEC 1
J 0
(4125 4025);
DISPLAY 0.680851 (4125 4025);
PAINT MONO (4125 4025);
DISPLAY INVISIBLE (4125 4025);
FORCEADD Q_CAP..1
(4150 2500);
FORCEPROP 1 LAST TOLERANCE 20%
J 0
(4200 2450);
DISPLAY 0.510638 (4200 2450);
PAINT SKYBLUE (4200 2450);
FORCEPROP 1 LAST MATERIAL X6S
J 0
(4200 2400);
DISPLAY 0.510638 (4200 2400);
PAINT SKYBLUE (4200 2400);
FORCEPROP 1 LAST VALUE 22UF
J 0
(4200 2550);
DISPLAY 0.510638 (4200 2550);
PAINT SKYBLUE (4200 2550);
FORCEPROP 1 LAST VOLTAGE 6.3V
J 0
(4200 2500);
DISPLAY 0.510638 (4200 2500);
PAINT SKYBLUE (4200 2500);
FORCEPROP 1 LAST PART_NUMBER CH6221ME900
J 0
(4200 2350);
DISPLAY 0.510638 (4200 2350);
PAINT WHITE (4200 2350);
FORCEPROP 1 LAST PACK_TYPE C0603
J 0
(4200 2300);
DISPLAY 0.510638 (4200 2300);
PAINT SKYBLUE (4200 2300);
FORCEPROP 1 LAST PATH I169
J 0
(4200 2650);
DISPLAY 0.978723 (4200 2650);
PAINT WHITE (4200 2650);
DISPLAY INVISIBLE (4200 2650);
FORCEPROP 2 LAST CDS_LIB pure_quanta
J 0
(4150 2500);
DISPLAY INVISIBLE (4150 2500);
FORCEPROP 1 LAST LOCATION C124
J 0
(4200 2600);
DISPLAY 0.702128 (4200 2600);
PAINT YELLOW (4200 2600);
FORCEPROP 1 LASTPIN (4150 2600) $PN 1
J 0
(4160 2580);
DISPLAY 0.808511 (4160 2580);
PAINT WHITE (4160 2580);
FORCEPROP 1 LASTPIN (4150 2400) $PN 2
J 0
(4160 2380);
DISPLAY 0.808511 (4160 2380);
PAINT WHITE (4160 2380);
FORCEPROP 0 LAST $SEC 1
J 0
(4200 2650);
DISPLAY 0.680851 (4200 2650);
PAINT MONO (4200 2650);
DISPLAY INVISIBLE (4200 2650);
FORCEPROP 0 LAST CDS_SEC 1
J 0
(4200 2650);
DISPLAY 0.680851 (4200 2650);
DISPLAY INVISIBLE (4200 2650);
FORCEADD UNIVERSAL_POWER..1
(4250 2750);
FORCEPROP 3 LASTPIN (4250 2700) SIG_NAME P1V8_AUX\g
J 0
(4260 2710);
DISPLAY 0.659574 (4260 2710);
PAINT MONO (4260 2710);
DISPLAY INVISIBLE (4260 2710);
FORCEPROP 1 LAST HDL_POWER P1V8_AUX
J 1
(4250 2800);
DISPLAY 0.702128 (4250 2800);
PAINT GREEN (4250 2800);
FORCEPROP 1 LAST PATH I170
J 0
(4300 2775);
DISPLAY 0.872340 (4300 2775);
PAINT AQUA (4300 2775);
DISPLAY INVISIBLE (4300 2775);
FORCEPROP 2 LAST CDS_LIB logical_power
J 0
(4250 2750);
DISPLAY INVISIBLE (4250 2750);
FORCEADD Q_CAP..1
(4150 3200);
FORCEPROP 1 LAST VALUE 22UF
J 0
(4200 3250);
DISPLAY 0.510638 (4200 3250);
PAINT SKYBLUE (4200 3250);
FORCEPROP 1 LAST VOLTAGE 6.3V
J 0
(4200 3200);
DISPLAY 0.510638 (4200 3200);
PAINT SKYBLUE (4200 3200);
FORCEPROP 1 LAST PACK_TYPE C0603
J 0
(4200 3000);
DISPLAY 0.510638 (4200 3000);
PAINT SKYBLUE (4200 3000);
FORCEPROP 1 LAST PART_NUMBER CH6221ME900
J 0
(4200 3050);
DISPLAY 0.510638 (4200 3050);
PAINT WHITE (4200 3050);
FORCEPROP 1 LAST MATERIAL X6S
J 0
(4200 3100);
DISPLAY 0.510638 (4200 3100);
PAINT SKYBLUE (4200 3100);
FORCEPROP 1 LAST TOLERANCE 20%
J 0
(4200 3150);
DISPLAY 0.510638 (4200 3150);
PAINT SKYBLUE (4200 3150);
FORCEPROP 1 LAST PATH I171
J 0
(4200 3350);
DISPLAY 0.978723 (4200 3350);
PAINT WHITE (4200 3350);
DISPLAY INVISIBLE (4200 3350);
FORCEPROP 2 LAST CDS_LIB pure_quanta
J 0
(4150 3200);
DISPLAY INVISIBLE (4150 3200);
FORCEPROP 1 LAST LOCATION C123
J 0
(4200 3300);
DISPLAY 0.702128 (4200 3300);
PAINT YELLOW (4200 3300);
FORCEPROP 1 LASTPIN (4150 3300) $PN 1
J 0
(4160 3280);
DISPLAY 0.808511 (4160 3280);
PAINT WHITE (4160 3280);
FORCEPROP 1 LASTPIN (4150 3100) $PN 2
J 0
(4160 3080);
DISPLAY 0.808511 (4160 3080);
PAINT WHITE (4160 3080);
FORCEPROP 0 LAST $SEC 1
J 0
(4200 3350);
DISPLAY 0.680851 (4200 3350);
PAINT MONO (4200 3350);
DISPLAY INVISIBLE (4200 3350);
FORCEPROP 0 LAST CDS_SEC 1
J 0
(4200 3350);
DISPLAY 0.680851 (4200 3350);
DISPLAY INVISIBLE (4200 3350);
FORCEADD UNIVERSAL_POWER..1
(4250 3450);
FORCEPROP 3 LASTPIN (4250 3400) SIG_NAME P1V0_AUX\g
J 0
(4260 3410);
DISPLAY 0.659574 (4260 3410);
PAINT MONO (4260 3410);
DISPLAY INVISIBLE (4260 3410);
FORCEPROP 1 LAST HDL_POWER P1V0_AUX
J 1
(4250 3500);
DISPLAY 0.702128 (4250 3500);
PAINT GREEN (4250 3500);
FORCEPROP 1 LAST PATH I172
J 0
(4300 3475);
DISPLAY 0.872340 (4300 3475);
PAINT AQUA (4300 3475);
DISPLAY INVISIBLE (4300 3475);
FORCEPROP 2 LAST CDS_LIB logical_power
J 0
(4250 3450);
DISPLAY INVISIBLE (4250 3450);
FORCEADD Q_CAP..1
(4250 3825);
FORCEPROP 1 LAST VALUE 1UF
J 0
(4300 3875);
DISPLAY 0.510638 (4300 3875);
PAINT SKYBLUE (4300 3875);
FORCEPROP 1 LAST VOLTAGE 25V
J 0
(4300 3825);
DISPLAY 0.510638 (4300 3825);
PAINT SKYBLUE (4300 3825);
FORCEPROP 1 LAST MATERIAL X6S
J 0
(4300 3725);
DISPLAY 0.510638 (4300 3725);
PAINT SKYBLUE (4300 3725);
FORCEPROP 1 LAST TOLERANCE 10%
J 0
(4300 3775);
DISPLAY 0.510638 (4300 3775);
PAINT SKYBLUE (4300 3775);
FORCEPROP 1 LAST PACK_TYPE C0402
J 0
(4275 3675);
DISPLAY 0.510638 (4275 3675);
PAINT SKYBLUE (4275 3675);
FORCEPROP 1 LAST PATH I173
J 0
(4300 3975);
DISPLAY 0.978723 (4300 3975);
PAINT WHITE (4300 3975);
DISPLAY INVISIBLE (4300 3975);
FORCEPROP 1 LAST PART_NUMBER CH5104KEB02
J 0
(4300 3675);
DISPLAY 0.510638 (4300 3675);
PAINT WHITE (4300 3675);
DISPLAY INVISIBLE (4300 3675);
FORCEPROP 2 LAST CDS_LIB pure_quanta
J 0
(4250 3825);
DISPLAY INVISIBLE (4250 3825);
FORCEPROP 1 LAST LOCATION C127
J 0
(4300 3925);
DISPLAY 0.702128 (4300 3925);
PAINT YELLOW (4300 3925);
FORCEPROP 1 LASTPIN (4250 3925) $PN 1
J 0
(4260 3905);
DISPLAY 0.808511 (4260 3905);
PAINT WHITE (4260 3905);
FORCEPROP 1 LASTPIN (4250 3725) $PN 2
J 0
(4260 3705);
DISPLAY 0.808511 (4260 3705);
PAINT WHITE (4260 3705);
FORCEPROP 2 LAST $SEC 1
J 0
(4300 4025);
DISPLAY 0.680851 (4300 4025);
PAINT MONO (4300 4025);
DISPLAY INVISIBLE (4300 4025);
FORCEPROP 0 LAST CDS_SEC 1
J 0
(4300 4025);
DISPLAY 0.680851 (4300 4025);
PAINT MONO (4300 4025);
DISPLAY INVISIBLE (4300 4025);
FORCEADD Q_CAP..1
(4425 3825);
FORCEPROP 1 LAST VOLTAGE 25V
J 0
(4475 3825);
DISPLAY 0.510638 (4475 3825);
PAINT SKYBLUE (4475 3825);
FORCEPROP 1 LAST VALUE 1UF
J 0
(4475 3875);
DISPLAY 0.510638 (4475 3875);
PAINT SKYBLUE (4475 3875);
FORCEPROP 1 LAST PACK_TYPE C0402
J 0
(4450 3675);
DISPLAY 0.510638 (4450 3675);
PAINT SKYBLUE (4450 3675);
FORCEPROP 1 LAST TOLERANCE 10%
J 0
(4475 3775);
DISPLAY 0.510638 (4475 3775);
PAINT SKYBLUE (4475 3775);
FORCEPROP 1 LAST MATERIAL X6S
J 0
(4475 3725);
DISPLAY 0.510638 (4475 3725);
PAINT SKYBLUE (4475 3725);
FORCEPROP 1 LAST PATH I174
J 0
(4475 3975);
DISPLAY 0.978723 (4475 3975);
PAINT WHITE (4475 3975);
DISPLAY INVISIBLE (4475 3975);
FORCEPROP 1 LAST PART_NUMBER CH5104KEB02
J 0
(4475 3675);
DISPLAY 0.510638 (4475 3675);
PAINT WHITE (4475 3675);
DISPLAY INVISIBLE (4475 3675);
FORCEPROP 2 LAST CDS_LIB pure_quanta
J 0
(4425 3825);
DISPLAY INVISIBLE (4425 3825);
FORCEPROP 1 LAST LOCATION C129
J 0
(4475 3925);
DISPLAY 0.702128 (4475 3925);
PAINT YELLOW (4475 3925);
FORCEPROP 1 LASTPIN (4425 3925) $PN 1
J 0
(4435 3905);
DISPLAY 0.808511 (4435 3905);
PAINT WHITE (4435 3905);
FORCEPROP 1 LASTPIN (4425 3725) $PN 2
J 0
(4435 3705);
DISPLAY 0.808511 (4435 3705);
PAINT WHITE (4435 3705);
FORCEPROP 2 LAST $SEC 1
J 0
(4475 4025);
DISPLAY 0.680851 (4475 4025);
PAINT MONO (4475 4025);
DISPLAY INVISIBLE (4475 4025);
FORCEPROP 0 LAST CDS_SEC 1
J 0
(4475 4025);
DISPLAY 0.680851 (4475 4025);
PAINT MONO (4475 4025);
DISPLAY INVISIBLE (4475 4025);
FORCEADD UNIVERSAL_GND..1
(4725 3550);
FORCEPROP 3 LASTPIN (4725 3600) SIG_NAME GND\g
J 0
(4735 3610);
DISPLAY 0.659574 (4735 3610);
PAINT MONO (4735 3610);
DISPLAY INVISIBLE (4735 3610);
FORCEPROP 1 LAST PATH I175
J 0
(4800 3550);
DISPLAY 0.872340 (4800 3550);
PAINT AQUA (4800 3550);
DISPLAY INVISIBLE (4800 3550);
FORCEPROP 1 LAST HDL_POWER GND
J 1
(4750 3475);
DISPLAY 0.702128 (4750 3475);
PAINT GREEN (4750 3475);
DISPLAY INVISIBLE (4750 3475);
FORCEPROP 2 LAST CDS_LIB logical_power
J 0
(4725 3550);
DISPLAY INVISIBLE (4725 3550);
FORCEADD UNIVERSAL_POWER..1
(4925 4075);
FORCEPROP 3 LASTPIN (4925 4025) SIG_NAME P1V2_AUX\g
J 0
(4935 4035);
DISPLAY 0.659574 (4935 4035);
PAINT MONO (4935 4035);
DISPLAY INVISIBLE (4935 4035);
FORCEPROP 1 LAST HDL_POWER P1V2_AUX
J 1
(4925 4125);
DISPLAY 0.702128 (4925 4125);
PAINT GREEN (4925 4125);
FORCEPROP 1 LAST PATH I178
J 0
(4975 4100);
DISPLAY 0.872340 (4975 4100);
PAINT AQUA (4975 4100);
DISPLAY INVISIBLE (4975 4100);
FORCEPROP 2 LAST CDS_LIB logical_power
J 0
(4925 4075);
DISPLAY INVISIBLE (4925 4075);
FORCEADD Q_CAP..1
(2775 3825);
FORCEPROP 1 LAST VOLTAGE 25V
J 0
(2825 3825);
DISPLAY 0.510638 (2825 3825);
PAINT SKYBLUE (2825 3825);
FORCEPROP 1 LAST VALUE 0.1UF
J 0
(2825 3875);
DISPLAY 0.510638 (2825 3875);
PAINT SKYBLUE (2825 3875);
FORCEPROP 1 LAST TOLERANCE 10%
J 0
(2825 3775);
DISPLAY 0.510638 (2825 3775);
PAINT SKYBLUE (2825 3775);
FORCEPROP 1 LAST MATERIAL X7R
J 0
(2825 3725);
DISPLAY 0.510638 (2825 3725);
PAINT SKYBLUE (2825 3725);
FORCEPROP 1 LAST PACK_TYPE 0402
J 0
(2825 3675);
DISPLAY 0.510638 (2825 3675);
PAINT SKYBLUE (2825 3675);
FORCEPROP 1 LAST PATH I179
J 0
(2825 3975);
DISPLAY 0.978723 (2825 3975);
PAINT WHITE (2825 3975);
DISPLAY INVISIBLE (2825 3975);
FORCEPROP 1 LAST PART_NUMBER CH4104K1B00
J 0
(2800 3600);
DISPLAY 0.510638 (2800 3600);
PAINT WHITE (2800 3600);
DISPLAY INVISIBLE (2800 3600);
FORCEPROP 2 LAST CDS_LIB pure_quanta
J 0
(2775 3825);
DISPLAY INVISIBLE (2775 3825);
FORCEPROP 1 LAST LOCATION C84
J 0
(2825 3925);
DISPLAY 0.702128 (2825 3925);
PAINT YELLOW (2825 3925);
FORCEPROP 1 LASTPIN (2775 3925) $PN 1
J 0
(2785 3905);
DISPLAY 0.808511 (2785 3905);
PAINT WHITE (2785 3905);
FORCEPROP 1 LASTPIN (2775 3725) $PN 2
J 0
(2785 3705);
DISPLAY 0.808511 (2785 3705);
PAINT WHITE (2785 3705);
FORCEPROP 2 LAST $SEC 1
J 0
(2825 4025);
DISPLAY 0.680851 (2825 4025);
PAINT MONO (2825 4025);
DISPLAY INVISIBLE (2825 4025);
FORCEPROP 0 LAST CDS_SEC 1
J 0
(2825 4025);
DISPLAY 0.680851 (2825 4025);
PAINT MONO (2825 4025);
DISPLAY INVISIBLE (2825 4025);
FORCEADD Q_CAP..1
(2600 3825);
FORCEPROP 1 LAST TOLERANCE 10%
J 0
(2650 3775);
DISPLAY 0.510638 (2650 3775);
PAINT SKYBLUE (2650 3775);
FORCEPROP 1 LAST VALUE 0.1UF
J 0
(2650 3875);
DISPLAY 0.510638 (2650 3875);
PAINT SKYBLUE (2650 3875);
FORCEPROP 1 LAST MATERIAL X7R
J 0
(2650 3725);
DISPLAY 0.510638 (2650 3725);
PAINT SKYBLUE (2650 3725);
FORCEPROP 1 LAST VOLTAGE 25V
J 0
(2650 3825);
DISPLAY 0.510638 (2650 3825);
PAINT SKYBLUE (2650 3825);
FORCEPROP 1 LAST PART_NUMBER CH4104K1B00
J 0
(2625 3600);
DISPLAY 0.510638 (2625 3600);
PAINT WHITE (2625 3600);
FORCEPROP 1 LAST PACK_TYPE 0402
J 0
(2650 3675);
DISPLAY 0.510638 (2650 3675);
PAINT SKYBLUE (2650 3675);
FORCEPROP 1 LAST PATH I180
J 0
(2650 3975);
DISPLAY 0.978723 (2650 3975);
PAINT WHITE (2650 3975);
DISPLAY INVISIBLE (2650 3975);
FORCEPROP 2 LAST CDS_LIB pure_quanta
J 0
(2600 3825);
DISPLAY INVISIBLE (2600 3825);
FORCEPROP 1 LAST LOCATION C82
J 0
(2650 3925);
DISPLAY 0.702128 (2650 3925);
PAINT YELLOW (2650 3925);
FORCEPROP 1 LASTPIN (2600 3925) $PN 1
J 0
(2610 3905);
DISPLAY 0.808511 (2610 3905);
PAINT WHITE (2610 3905);
FORCEPROP 1 LASTPIN (2600 3725) $PN 2
J 0
(2610 3705);
DISPLAY 0.808511 (2610 3705);
PAINT WHITE (2610 3705);
FORCEPROP 0 LAST $SEC 1
J 0
(2650 3975);
DISPLAY 0.680851 (2650 3975);
PAINT MONO (2650 3975);
DISPLAY INVISIBLE (2650 3975);
FORCEPROP 0 LAST CDS_SEC 1
J 0
(2650 3975);
DISPLAY 0.680851 (2650 3975);
DISPLAY INVISIBLE (2650 3975);
FORCEADD OFFPAGE..1
(-700 2150);
FORCEPROP 2 LAST $XR0 17 
J 0
(-921 2150);
DISPLAY 0.638298 (-921 2150);
PAINT MONO (-921 2150);
FORCEPROP 2 LAST PATH I182
J 0
(-900 2200);
DISPLAY 1.021277 (-900 2200);
DISPLAY INVISIBLE (-900 2200);
FORCEPROP 1 LAST COMMENT_BODY TRUE
J 0
(-575 2050);
DISPLAY 0.872340 (-575 2050);
PAINT PEACH (-575 2050);
DISPLAY INVISIBLE (-575 2050);
FORCEPROP 1 LAST OFFPAGE TRUE
J 0
(-375 2025);
DISPLAY 0.872340 (-375 2025);
PAINT GREEN (-375 2025);
DISPLAY INVISIBLE (-375 2025);
FORCEPROP 2 LAST CDS_LIB standard
J 0
(-700 2150);
DISPLAY INVISIBLE (-700 2150);
FORCEADD Q_CAP..1
(-775 1425);
FORCEPROP 1 LAST PACK_TYPE 0402
J 0
(-725 1275);
DISPLAY 0.510638 (-725 1275);
PAINT SKYBLUE (-725 1275);
FORCEPROP 1 LAST VALUE 0.1UF
J 0
(-725 1475);
DISPLAY 0.510638 (-725 1475);
PAINT SKYBLUE (-725 1475);
FORCEPROP 1 LAST TOLERANCE 10%
J 0
(-725 1375);
DISPLAY 0.510638 (-725 1375);
PAINT SKYBLUE (-725 1375);
FORCEPROP 1 LAST MATERIAL X7R
J 0
(-725 1325);
DISPLAY 0.510638 (-725 1325);
PAINT SKYBLUE (-725 1325);
FORCEPROP 1 LAST PART_NUMBER CH4104K1B00
J 0
(-625 1400);
DISPLAY 0.510638 (-625 1400);
PAINT WHITE (-625 1400);
FORCEPROP 1 LAST VOLTAGE 25V
J 0
(-725 1425);
DISPLAY 0.510638 (-725 1425);
PAINT SKYBLUE (-725 1425);
FORCEPROP 1 LAST PATH I183
J 0
(-725 1575);
DISPLAY 0.978723 (-725 1575);
PAINT WHITE (-725 1575);
DISPLAY INVISIBLE (-725 1575);
FORCEPROP 2 LAST CDS_LIB pure_quanta
J 0
(-775 1425);
DISPLAY INVISIBLE (-775 1425);
FORCEPROP 1 LAST LOCATION C76
J 0
(-725 1525);
DISPLAY 0.702128 (-725 1525);
PAINT YELLOW (-725 1525);
FORCEPROP 1 LASTPIN (-775 1525) $PN 1
J 0
(-765 1505);
DISPLAY 0.808511 (-765 1505);
PAINT WHITE (-765 1505);
FORCEPROP 1 LASTPIN (-775 1325) $PN 2
J 0
(-765 1305);
DISPLAY 0.808511 (-765 1305);
PAINT WHITE (-765 1305);
FORCEPROP 2 LAST $SEC 1
J 0
(-725 1625);
DISPLAY 0.680851 (-725 1625);
PAINT MONO (-725 1625);
DISPLAY INVISIBLE (-725 1625);
FORCEPROP 0 LAST CDS_SEC 1
J 0
(-725 1625);
DISPLAY 0.680851 (-725 1625);
PAINT MONO (-725 1625);
DISPLAY INVISIBLE (-725 1625);
FORCEADD UNIVERSAL_GND..1
(4075 450);
FORCEPROP 3 LASTPIN (4075 500) SIG_NAME GND\g
J 0
(4085 510);
DISPLAY 0.659574 (4085 510);
PAINT MONO (4085 510);
DISPLAY INVISIBLE (4085 510);
FORCEPROP 1 LAST PATH I184
J 0
(4150 450);
DISPLAY 0.872340 (4150 450);
PAINT AQUA (4150 450);
DISPLAY INVISIBLE (4150 450);
FORCEPROP 1 LAST HDL_POWER GND
J 1
(4100 375);
DISPLAY 0.702128 (4100 375);
PAINT GREEN (4100 375);
DISPLAY INVISIBLE (4100 375);
FORCEPROP 2 LAST CDS_LIB logical_power
J 0
(4075 450);
DISPLAY INVISIBLE (4075 450);
FORCEADD OFFPAGE..1
(-525 3550);
FORCEPROP 2 LAST $XR0 17 
J 0
(-746 3550);
DISPLAY 0.638298 (-746 3550);
PAINT MONO (-746 3550);
FORCEPROP 2 LAST PATH I185
J 0
(-475 3625);
DISPLAY 1.021277 (-475 3625);
DISPLAY INVISIBLE (-475 3625);
FORCEPROP 1 LAST COMMENT_BODY TRUE
J 0
(-400 3450);
DISPLAY 0.872340 (-400 3450);
PAINT PEACH (-400 3450);
DISPLAY INVISIBLE (-400 3450);
FORCEPROP 1 LAST OFFPAGE TRUE
J 0
(-200 3425);
DISPLAY 0.872340 (-200 3425);
PAINT GREEN (-200 3425);
DISPLAY INVISIBLE (-200 3425);
FORCEPROP 2 LAST CDS_LIB standard
J 0
(-525 3550);
DISPLAY INVISIBLE (-525 3550);
FORCEADD OFFPAGE..1
(-525 3800);
FORCEPROP 2 LAST $XR0 17 
J 0
(-746 3800);
DISPLAY 0.638298 (-746 3800);
PAINT MONO (-746 3800);
FORCEPROP 2 LAST PATH I186
J 0
(-475 3875);
DISPLAY 1.021277 (-475 3875);
DISPLAY INVISIBLE (-475 3875);
FORCEPROP 1 LAST COMMENT_BODY TRUE
J 0
(-400 3700);
DISPLAY 0.872340 (-400 3700);
PAINT PEACH (-400 3700);
DISPLAY INVISIBLE (-400 3700);
FORCEPROP 1 LAST OFFPAGE TRUE
J 0
(-200 3675);
DISPLAY 0.872340 (-200 3675);
PAINT GREEN (-200 3675);
DISPLAY INVISIBLE (-200 3675);
FORCEPROP 2 LAST CDS_LIB standard
J 0
(-525 3800);
DISPLAY INVISIBLE (-525 3800);
FORCEADD Q_RES..1
(-1450 3250);
FORCEPROP 1 LAST WATTAGE 1/16W
J 2
(-1475 3100);
DISPLAY 0.510638 (-1475 3100);
PAINT SKYBLUE (-1475 3100);
FORCEPROP 1 LAST TOLERANCE 1%
J 0
(-1450 3150);
DISPLAY 0.510638 (-1450 3150);
PAINT SKYBLUE (-1450 3150);
FORCEPROP 1 LAST PART_NUMBER CS22742FB05
J 0
(-1350 3150);
DISPLAY 0.510638 (-1350 3150);
PAINT WHITE (-1350 3150);
FORCEPROP 1 LAST PACK_TYPE 0402LF
J 0
(-1325 3100);
DISPLAY 0.510638 (-1325 3100);
PAINT SKYBLUE (-1325 3100);
FORCEPROP 1 LAST MATERIAL CHIP
J 0
(-1450 3100);
DISPLAY 0.510638 (-1450 3100);
PAINT SKYBLUE (-1450 3100);
FORCEPROP 1 LAST VALUE 2.74K
J 2
(-1475 3150);
DISPLAY 0.510638 (-1475 3150);
PAINT SKYBLUE (-1475 3150);
FORCEPROP 1 LAST PATH I187
J 0
(-1500 3400);
DISPLAY 0.978723 (-1500 3400);
PAINT WHITE (-1500 3400);
DISPLAY INVISIBLE (-1500 3400);
FORCEPROP 2 LAST CDS_LIB pure_quanta
J 0
(-1450 3250);
DISPLAY INVISIBLE (-1450 3250);
FORCEPROP 1 LAST LOCATION R235
J 0
(-1500 3300);
DISPLAY 0.702128 (-1500 3300);
PAINT YELLOW (-1500 3300);
FORCEPROP 0 LAST $SEC 1
J 0
(-1500 3350);
DISPLAY 0.680851 (-1500 3350);
PAINT MONO (-1500 3350);
DISPLAY INVISIBLE (-1500 3350);
FORCEPROP 0 LAST CDS_SEC 1
J 0
(-1500 3350);
DISPLAY 1.021277 (-1500 3350);
DISPLAY INVISIBLE (-1500 3350);
FORCEPROP 1 LASTPIN (-1550 3250) $PN 1
J 0
(-1538 3262);
DISPLAY 0.808511 (-1538 3262);
PAINT WHITE (-1538 3262);
DISPLAY INVISIBLE (-1538 3262);
FORCEPROP 1 LASTPIN (-1350 3250) $PN 2
J 0
(-1388 3262);
DISPLAY 0.808511 (-1388 3262);
PAINT WHITE (-1388 3262);
DISPLAY INVISIBLE (-1388 3262);
FORCEADD AST2600A3GP..5
(1125 2150);
FORCEPROP 2 LAST VALUE AST2600A3-GP
J 0
(450 4500);
DISPLAY 0.680851 (450 4500);
FORCEPROP 2 LAST PART_TYPE SMLF
J 0
(450 4550);
DISPLAY 0.680851 (450 4550);
FORCEPROP 1 LAST PART_NUMBER AJ026000T06
J 0
(428 4302);
DISPLAY 0.723404 (428 4302);
FORCEPROP 1 LAST MATERIAL IC
J 0
(428 4175);
DISPLAY 0.723404 (428 4175);
FORCEPROP 2 LAST CDS_LIB pure_quanta
J 0
(1125 2150);
DISPLAY INVISIBLE (1125 2150);
FORCEPROP 1 LAST PATH I188
J 0
(1125 2150);
DISPLAY 0.723404 (1125 2150);
DISPLAY INVISIBLE (1125 2150);
FORCEPROP 1 LAST CDS_LMAN_SYM_OUTLINE -700,2000,700,-2000
J 0
(1125 2150);
DISPLAY 0.468085 (1125 2150);
PAINT GREEN (1125 2150);
DISPLAY INVISIBLE (1125 2150);
FORCEPROP 1 LAST NEEDS_NO_SIZE TRUE
J 0
(1125 2150);
DISPLAY 0.723404 (1125 2150);
DISPLAY INVISIBLE (1125 2150);
FORCEPROP 1 LAST LOCATION U5
J 0
(428 4449);
DISPLAY 0.723404 (428 4449);
FORCEPROP 0 LASTPIN (275 4050) $PN AA21
J 2
(265 4060);
DISPLAY 0.680851 (265 4060);
PAINT MONO (265 4060);
FORCEPROP 0 LASTPIN (275 4100) $PN Y21
J 2
(265 4110);
DISPLAY 0.680851 (265 4110);
PAINT MONO (265 4110);
FORCEPROP 0 LASTPIN (275 3850) $PN AF20
J 2
(265 3860);
DISPLAY 0.680851 (265 3860);
PAINT MONO (265 3860);
FORCEPROP 0 LASTPIN (275 3600) $PN AF18
J 2
(265 3610);
DISPLAY 0.680851 (265 3610);
PAINT MONO (265 3610);
FORCEPROP 0 LASTPIN (275 3800) $PN AF19
J 2
(265 3810);
DISPLAY 0.680851 (265 3810);
PAINT MONO (265 3810);
FORCEPROP 0 LASTPIN (275 3550) $PN AF17
J 2
(265 3560);
DISPLAY 0.680851 (265 3560);
PAINT MONO (265 3560);
FORCEPROP 0 LASTPIN (275 3900) $PN AB20
J 2
(265 3910);
DISPLAY 0.680851 (265 3910);
PAINT MONO (265 3910);
FORCEPROP 0 LASTPIN (275 3650) $PN AD18
J 2
(265 3660);
DISPLAY 0.680851 (265 3660);
PAINT MONO (265 3660);
FORCEPROP 0 LASTPIN (275 3950) $PN AC20
J 2
(265 3960);
DISPLAY 0.680851 (265 3960);
PAINT MONO (265 3960);
FORCEPROP 0 LASTPIN (275 3700) $PN AD17
J 2
(265 3710);
DISPLAY 0.680851 (265 3710);
PAINT MONO (265 3710);
FORCEPROP 0 LASTPIN (275 1700) $PN N5
J 2
(265 1710);
DISPLAY 0.680851 (265 1710);
PAINT MONO (265 1710);
FORCEPROP 0 LASTPIN (1975 200) $PN V23
J 0
(1985 210);
DISPLAY 0.680851 (1985 210);
PAINT MONO (1985 210);
FORCEPROP 0 LASTPIN (275 3400) $PN V21
J 2
(265 3410);
DISPLAY 0.680851 (265 3410);
PAINT MONO (265 3410);
FORCEPROP 0 LASTPIN (275 3350) $PN W21
J 2
(265 3360);
DISPLAY 0.680851 (265 3360);
PAINT MONO (265 3360);
FORCEPROP 0 LASTPIN (275 3250) $PN AC21
J 2
(265 3260);
DISPLAY 0.680851 (265 3260);
PAINT MONO (265 3260);
FORCEPROP 0 LASTPIN (275 1950) $PN T8
J 2
(265 1960);
DISPLAY 0.680851 (265 1960);
PAINT MONO (265 1960);
FORCEPROP 0 LASTPIN (275 1850) $PN V8
J 2
(265 1860);
DISPLAY 0.680851 (265 1860);
PAINT MONO (265 1860);
FORCEPROP 0 LASTPIN (275 3100) $PN J9
J 2
(265 3110);
DISPLAY 0.680851 (265 3110);
PAINT MONO (265 3110);
FORCEPROP 0 LASTPIN (275 300) $PN F19
J 2
(265 310);
DISPLAY 0.680851 (265 310);
PAINT MONO (265 310);
FORCEPROP 0 LASTPIN (275 250) $PN F20
J 2
(265 260);
DISPLAY 0.680851 (265 260);
PAINT MONO (265 260);
FORCEPROP 0 LASTPIN (275 1100) $PN V22
J 2
(265 1110);
DISPLAY 0.680851 (265 1110);
PAINT MONO (265 1110);
FORCEPROP 0 LASTPIN (275 1000) $PN U21
J 2
(265 1010);
DISPLAY 0.680851 (265 1010);
PAINT MONO (265 1010);
FORCEPROP 0 LASTPIN (1975 2950) $PN L9
J 0
(1985 2960);
DISPLAY 0.680851 (1985 2960);
PAINT MONO (1985 2960);
FORCEPROP 0 LASTPIN (1975 2900) $PN L10
J 0
(1985 2910);
DISPLAY 0.680851 (1985 2910);
PAINT MONO (1985 2910);
FORCEPROP 0 LASTPIN (1975 2850) $PN M8
J 0
(1985 2860);
DISPLAY 0.680851 (1985 2860);
PAINT MONO (1985 2860);
FORCEPROP 0 LASTPIN (1975 2700) $PN M11
J 0
(1985 2710);
DISPLAY 0.680851 (1985 2710);
PAINT MONO (1985 2710);
FORCEPROP 0 LASTPIN (1975 2800) $PN N8
J 0
(1985 2810);
DISPLAY 0.680851 (1985 2810);
PAINT MONO (1985 2810);
FORCEPROP 0 LASTPIN (1975 2650) $PN N11
J 0
(1985 2660);
DISPLAY 0.680851 (1985 2660);
PAINT MONO (1985 2660);
FORCEPROP 0 LASTPIN (1975 2750) $PN P8
J 0
(1985 2760);
DISPLAY 0.680851 (1985 2760);
PAINT MONO (1985 2760);
FORCEPROP 0 LASTPIN (1975 2600) $PN P11
J 0
(1985 2610);
DISPLAY 0.680851 (1985 2610);
PAINT MONO (1985 2610);
FORCEPROP 0 LASTPIN (1975 2550) $PN R9
J 0
(1985 2560);
DISPLAY 0.680851 (1985 2560);
PAINT MONO (1985 2560);
FORCEPROP 0 LASTPIN (1975 2500) $PN R10
J 0
(1985 2510);
DISPLAY 0.680851 (1985 2510);
PAINT MONO (1985 2510);
FORCEPROP 0 LASTPIN (1975 4000) $PN K16
J 0
(1985 4010);
DISPLAY 0.680851 (1985 4010);
PAINT MONO (1985 4010);
FORCEPROP 0 LASTPIN (1975 3950) $PN K17
J 0
(1985 3960);
DISPLAY 0.680851 (1985 3960);
PAINT MONO (1985 3960);
FORCEPROP 0 LASTPIN (1975 3900) $PN K18
J 0
(1985 3910);
DISPLAY 0.680851 (1985 3910);
PAINT MONO (1985 3910);
FORCEPROP 0 LASTPIN (1975 3850) $PN K19
J 0
(1985 3860);
DISPLAY 0.680851 (1985 3860);
PAINT MONO (1985 3860);
FORCEPROP 0 LASTPIN (1975 3800) $PN L14
J 0
(1985 3810);
DISPLAY 0.680851 (1985 3810);
PAINT MONO (1985 3810);
FORCEPROP 0 LASTPIN (1975 3500) $PN L21
J 0
(1985 3510);
DISPLAY 0.680851 (1985 3510);
PAINT MONO (1985 3510);
FORCEPROP 0 LASTPIN (1975 3750) $PN M14
J 0
(1985 3760);
DISPLAY 0.680851 (1985 3760);
PAINT MONO (1985 3760);
FORCEPROP 0 LASTPIN (1975 3450) $PN M21
J 0
(1985 3460);
DISPLAY 0.680851 (1985 3460);
PAINT MONO (1985 3460);
FORCEPROP 0 LASTPIN (1975 3700) $PN N14
J 0
(1985 3710);
DISPLAY 0.680851 (1985 3710);
PAINT MONO (1985 3710);
FORCEPROP 0 LASTPIN (1975 3400) $PN N21
J 0
(1985 3410);
DISPLAY 0.680851 (1985 3410);
PAINT MONO (1985 3410);
FORCEPROP 0 LASTPIN (1975 3650) $PN P14
J 0
(1985 3660);
DISPLAY 0.680851 (1985 3660);
PAINT MONO (1985 3660);
FORCEPROP 0 LASTPIN (1975 3350) $PN P21
J 0
(1985 3360);
DISPLAY 0.680851 (1985 3360);
PAINT MONO (1985 3360);
FORCEPROP 0 LASTPIN (1975 3600) $PN R14
J 0
(1985 3610);
DISPLAY 0.680851 (1985 3610);
PAINT MONO (1985 3610);
FORCEPROP 0 LASTPIN (1975 3300) $PN R21
J 0
(1985 3310);
DISPLAY 0.680851 (1985 3310);
PAINT MONO (1985 3310);
FORCEPROP 0 LASTPIN (1975 3550) $PN T14
J 0
(1985 3560);
DISPLAY 0.680851 (1985 3560);
PAINT MONO (1985 3560);
FORCEPROP 0 LASTPIN (1975 3250) $PN T21
J 0
(1985 3260);
DISPLAY 0.680851 (1985 3260);
PAINT MONO (1985 3260);
FORCEPROP 0 LASTPIN (1975 3200) $PN U15
J 0
(1985 3210);
DISPLAY 0.680851 (1985 3210);
PAINT MONO (1985 3210);
FORCEPROP 0 LASTPIN (1975 3150) $PN U16
J 0
(1985 3160);
DISPLAY 0.680851 (1985 3160);
PAINT MONO (1985 3160);
FORCEPROP 0 LASTPIN (1975 3100) $PN U17
J 0
(1985 3110);
DISPLAY 0.680851 (1985 3110);
PAINT MONO (1985 3110);
FORCEPROP 0 LASTPIN (1975 3050) $PN U18
J 0
(1985 3060);
DISPLAY 0.680851 (1985 3060);
PAINT MONO (1985 3060);
FORCEPROP 0 LASTPIN (1975 300) $PN W15
J 0
(1985 310);
DISPLAY 0.680851 (1985 310);
PAINT MONO (1985 310);
FORCEPROP 0 LASTPIN (275 1200) $PN M6
J 2
(265 1210);
DISPLAY 0.680851 (265 1210);
PAINT MONO (265 1210);
FORCEPROP 0 LASTPIN (275 1600) $PN G6
J 2
(265 1610);
DISPLAY 0.680851 (265 1610);
PAINT MONO (265 1610);
FORCEPROP 0 LASTPIN (275 1550) $PN H6
J 2
(265 1560);
DISPLAY 0.680851 (265 1560);
PAINT MONO (265 1560);
FORCEPROP 0 LASTPIN (275 1500) $PN J6
J 2
(265 1510);
DISPLAY 0.680851 (265 1510);
PAINT MONO (265 1510);
FORCEPROP 0 LASTPIN (275 1450) $PN K6
J 2
(265 1460);
DISPLAY 0.680851 (265 1460);
PAINT MONO (265 1460);
FORCEPROP 0 LASTPIN (275 1400) $PN L6
J 2
(265 1410);
DISPLAY 0.680851 (265 1410);
PAINT MONO (265 1410);
FORCEPROP 0 LASTPIN (275 1350) $PN P6
J 2
(265 1360);
DISPLAY 0.680851 (265 1360);
PAINT MONO (265 1360);
FORCEPROP 0 LASTPIN (275 1300) $PN R6
J 2
(265 1310);
DISPLAY 0.680851 (265 1310);
PAINT MONO (265 1310);
FORCEPROP 0 LASTPIN (275 1250) $PN T6
J 2
(265 1260);
DISPLAY 0.680851 (265 1260);
PAINT MONO (265 1260);
FORCEPROP 0 LASTPIN (275 2250) $PN T10
J 2
(265 2260);
DISPLAY 0.680851 (265 2260);
PAINT MONO (265 2260);
FORCEPROP 0 LASTPIN (275 2150) $PN V10
J 2
(265 2160);
DISPLAY 0.680851 (265 2160);
PAINT MONO (265 2160);
FORCEPROP 0 LASTPIN (275 2700) $PN H14
J 2
(265 2710);
DISPLAY 0.680851 (265 2710);
PAINT MONO (265 2710);
FORCEPROP 0 LASTPIN (275 3000) $PN E7
J 2
(265 3010);
DISPLAY 0.680851 (265 3010);
PAINT MONO (265 3010);
FORCEPROP 0 LASTPIN (275 2950) $PN F7
J 2
(265 2960);
DISPLAY 0.680851 (265 2960);
PAINT MONO (265 2960);
FORCEPROP 0 LASTPIN (275 2850) $PN E9
J 2
(265 2860);
DISPLAY 0.680851 (265 2860);
PAINT MONO (265 2860);
FORCEPROP 0 LASTPIN (275 2800) $PN F9
J 2
(265 2810);
DISPLAY 0.680851 (265 2810);
PAINT MONO (265 2810);
FORCEPROP 0 LASTPIN (1975 2200) $PN H8
J 0
(1985 2210);
DISPLAY 0.680851 (1985 2210);
PAINT MONO (1985 2210);
FORCEPROP 0 LASTPIN (1975 2150) $PN J8
J 0
(1985 2160);
DISPLAY 0.680851 (1985 2160);
PAINT MONO (1985 2160);
FORCEPROP 0 LASTPIN (1975 2100) $PN N12
J 0
(1985 2110);
DISPLAY 0.680851 (1985 2110);
PAINT MONO (1985 2110);
FORCEPROP 0 LASTPIN (1975 2050) $PN P12
J 0
(1985 2060);
DISPLAY 0.680851 (1985 2060);
PAINT MONO (1985 2060);
FORCEPROP 0 LASTPIN (1975 2000) $PN R12
J 0
(1985 2010);
DISPLAY 0.680851 (1985 2010);
PAINT MONO (1985 2010);
FORCEPROP 0 LASTPIN (1975 1900) $PN H12
J 0
(1985 1910);
DISPLAY 0.680851 (1985 1910);
PAINT MONO (1985 1910);
FORCEPROP 0 LASTPIN (1975 1850) $PN J12
J 0
(1985 1860);
DISPLAY 0.680851 (1985 1860);
PAINT MONO (1985 1860);
FORCEPROP 0 LASTPIN (1975 900) $PN L13
J 0
(1985 910);
DISPLAY 0.680851 (1985 910);
PAINT MONO (1985 910);
FORCEPROP 0 LASTPIN (1975 850) $PN M13
J 0
(1985 860);
DISPLAY 0.680851 (1985 860);
PAINT MONO (1985 860);
FORCEPROP 0 LASTPIN (1975 800) $PN N13
J 0
(1985 810);
DISPLAY 0.680851 (1985 810);
PAINT MONO (1985 810);
FORCEPROP 0 LASTPIN (1975 750) $PN P13
J 0
(1985 760);
DISPLAY 0.680851 (1985 760);
PAINT MONO (1985 760);
FORCEPROP 0 LASTPIN (1975 700) $PN R13
J 0
(1985 710);
DISPLAY 0.680851 (1985 710);
PAINT MONO (1985 710);
FORCEPROP 0 LASTPIN (1975 650) $PN T13
J 0
(1985 660);
DISPLAY 0.680851 (1985 660);
PAINT MONO (1985 660);
FORCEPROP 0 LASTPIN (1975 600) $PN U13
J 0
(1985 610);
DISPLAY 0.680851 (1985 610);
PAINT MONO (1985 610);
FORCEPROP 0 LASTPIN (1975 550) $PN V13
J 0
(1985 560);
DISPLAY 0.680851 (1985 560);
PAINT MONO (1985 560);
FORCEPROP 0 LASTPIN (1975 500) $PN W13
J 0
(1985 510);
DISPLAY 0.680851 (1985 510);
PAINT MONO (1985 510);
FORCEPROP 0 LASTPIN (1975 450) $PN W14
J 0
(1985 460);
DISPLAY 0.680851 (1985 460);
PAINT MONO (1985 460);
FORCEPROP 0 LASTPIN (1975 2300) $PN U6
J 0
(1985 2310);
DISPLAY 0.680851 (1985 2310);
PAINT MONO (1985 2310);
FORCEPROP 0 LASTPIN (1975 2250) $PN V6
J 0
(1985 2260);
DISPLAY 0.680851 (1985 2260);
PAINT MONO (1985 2260);
FORCEPROP 0 LASTPIN (1975 1700) $PN H15
J 0
(1985 1710);
DISPLAY 0.680851 (1985 1710);
PAINT MONO (1985 1710);
FORCEPROP 0 LASTPIN (1975 1650) $PN H16
J 0
(1985 1660);
DISPLAY 0.680851 (1985 1660);
PAINT MONO (1985 1660);
FORCEPROP 0 LASTPIN (1975 1600) $PN H17
J 0
(1985 1610);
DISPLAY 0.680851 (1985 1610);
PAINT MONO (1985 1610);
FORCEPROP 0 LASTPIN (1975 1350) $PN N22
J 0
(1985 1360);
DISPLAY 0.680851 (1985 1360);
PAINT MONO (1985 1360);
FORCEPROP 0 LASTPIN (1975 1300) $PN P22
J 0
(1985 1310);
DISPLAY 0.680851 (1985 1310);
PAINT MONO (1985 1310);
FORCEPROP 0 LASTPIN (1975 1250) $PN R22
J 0
(1985 1260);
DISPLAY 0.680851 (1985 1260);
PAINT MONO (1985 1260);
FORCEPROP 0 LASTPIN (1975 1100) $PN K11
J 0
(1985 1110);
DISPLAY 0.680851 (1985 1110);
PAINT MONO (1985 1110);
FORCEPROP 0 LASTPIN (1975 1050) $PN K12
J 0
(1985 1060);
DISPLAY 0.680851 (1985 1060);
PAINT MONO (1985 1060);
FORCEPROP 0 LASTPIN (1975 1200) $PN T22
J 0
(1985 1210);
DISPLAY 0.680851 (1985 1210);
PAINT MONO (1985 1210);
FORCEPROP 0 LASTPIN (1975 1550) $PN W16
J 0
(1985 1560);
DISPLAY 0.680851 (1985 1560);
PAINT MONO (1985 1560);
FORCEPROP 0 LASTPIN (1975 1500) $PN W17
J 0
(1985 1510);
DISPLAY 0.680851 (1985 1510);
PAINT MONO (1985 1510);
FORCEPROP 0 LASTPIN (1975 1450) $PN W18
J 0
(1985 1460);
DISPLAY 0.680851 (1985 1460);
PAINT MONO (1985 1460);
FORCEPROP 0 LASTPIN (1975 1400) $PN W19
J 0
(1985 1410);
DISPLAY 0.680851 (1985 1410);
PAINT MONO (1985 1410);
FORCEPROP 0 LASTPIN (275 2550) $PN T9
J 2
(265 2560);
DISPLAY 0.680851 (265 2560);
PAINT MONO (265 2560);
FORCEPROP 0 LASTPIN (275 2450) $PN V9
J 2
(265 2460);
DISPLAY 0.680851 (265 2460);
PAINT MONO (265 2460);
FORCEPROP 0 LASTPIN (275 750) $PN J21
J 2
(265 760);
DISPLAY 0.680851 (265 760);
PAINT MONO (265 760);
FORCEPROP 0 LASTPIN (275 700) $PN K21
J 2
(265 710);
DISPLAY 0.680851 (265 710);
PAINT MONO (265 710);
FORCEPROP 0 LASTPIN (275 900) $PN L22
J 2
(265 910);
DISPLAY 0.680851 (265 910);
PAINT MONO (265 910);
FORCEPROP 0 LASTPIN (275 850) $PN M22
J 2
(265 860);
DISPLAY 0.680851 (265 860);
PAINT MONO (265 860);
FORCEPROP 0 LASTPIN (275 600) $PN G21
J 2
(265 610);
DISPLAY 0.680851 (265 610);
PAINT MONO (265 610);
FORCEPROP 0 LASTPIN (275 550) $PN H21
J 2
(265 560);
DISPLAY 0.680851 (265 560);
PAINT MONO (265 560);
FORCEPROP 0 LASTPIN (275 450) $PN H18
J 2
(265 460);
DISPLAY 0.680851 (265 460);
PAINT MONO (265 460);
FORCEPROP 0 LASTPIN (275 400) $PN H19
J 2
(265 410);
DISPLAY 0.680851 (265 410);
PAINT MONO (265 410);
FORCEPROP 0 LAST $SEC 5
J 0
(450 4600);
DISPLAY 0.680851 (450 4600);
PAINT MONO (450 4600);
DISPLAY INVISIBLE (450 4600);
FORCEPROP 0 LAST CDS_SEC 5
J 0
(450 4600);
DISPLAY 0.680851 (450 4600);
DISPLAY INVISIBLE (450 4600);
FORCEADD Q_CAP..1
(3750 3200);
FORCEPROP 1 LAST TOLERANCE 20%
J 0
(3800 3150);
DISPLAY 0.510638 (3800 3150);
PAINT SKYBLUE (3800 3150);
FORCEPROP 1 LAST MATERIAL X6S
J 0
(3800 3100);
DISPLAY 0.510638 (3800 3100);
PAINT SKYBLUE (3800 3100);
FORCEPROP 1 LAST VALUE 22UF
J 0
(3800 3250);
DISPLAY 0.510638 (3800 3250);
PAINT SKYBLUE (3800 3250);
FORCEPROP 1 LAST PACK_TYPE C0603
J 0
(3800 3050);
DISPLAY 0.510638 (3800 3050);
PAINT SKYBLUE (3800 3050);
FORCEPROP 1 LAST VOLTAGE 6.3V
J 0
(3800 3200);
DISPLAY 0.510638 (3800 3200);
PAINT SKYBLUE (3800 3200);
FORCEPROP 2 LAST CDS_LIB pure_quanta
J 0
(3750 3200);
DISPLAY INVISIBLE (3750 3200);
FORCEPROP 1 LAST PATH I189
J 0
(3800 3350);
DISPLAY 0.978723 (3800 3350);
PAINT WHITE (3800 3350);
DISPLAY INVISIBLE (3800 3350);
FORCEPROP 1 LAST PART_NUMBER CH6221ME900
J 0
(3800 3050);
DISPLAY 0.510638 (3800 3050);
PAINT WHITE (3800 3050);
DISPLAY INVISIBLE (3800 3050);
FORCEPROP 1 LAST LOCATION C113
J 0
(3800 3300);
DISPLAY 0.702128 (3800 3300);
PAINT YELLOW (3800 3300);
FORCEPROP 1 LASTPIN (3750 3300) $PN 1
J 0
(3760 3280);
DISPLAY 0.787234 (3760 3280);
PAINT MONO (3760 3280);
FORCEPROP 1 LASTPIN (3750 3100) $PN 2
J 0
(3760 3080);
DISPLAY 0.787234 (3760 3080);
PAINT MONO (3760 3080);
FORCEPROP 0 LAST $SEC 1
J 0
(3800 3350);
DISPLAY 0.680851 (3800 3350);
PAINT MONO (3800 3350);
DISPLAY INVISIBLE (3800 3350);
FORCEPROP 0 LAST CDS_SEC 1
J 0
(3800 3350);
DISPLAY 0.680851 (3800 3350);
DISPLAY INVISIBLE (3800 3350);
FORCEADD Q_CAP..1
(3950 1875);
FORCEPROP 1 LAST PACK_TYPE C0603
J 0
(4000 1725);
DISPLAY 0.510638 (4000 1725);
PAINT SKYBLUE (4000 1725);
FORCEPROP 1 LAST VOLTAGE 6.3V
J 0
(4000 1875);
DISPLAY 0.510638 (4000 1875);
PAINT SKYBLUE (4000 1875);
FORCEPROP 1 LAST VALUE 22UF
J 0
(4000 1925);
DISPLAY 0.510638 (4000 1925);
PAINT SKYBLUE (4000 1925);
FORCEPROP 1 LAST TOLERANCE 20%
J 0
(4000 1825);
DISPLAY 0.510638 (4000 1825);
PAINT SKYBLUE (4000 1825);
FORCEPROP 1 LAST MATERIAL X6S
J 0
(4000 1775);
DISPLAY 0.510638 (4000 1775);
PAINT SKYBLUE (4000 1775);
FORCEPROP 1 LAST PART_NUMBER CH6221ME900
J 0
(4000 1725);
DISPLAY 0.510638 (4000 1725);
PAINT WHITE (4000 1725);
DISPLAY INVISIBLE (4000 1725);
FORCEPROP 1 LAST PATH I190
J 0
(4000 2025);
DISPLAY 0.978723 (4000 2025);
PAINT WHITE (4000 2025);
DISPLAY INVISIBLE (4000 2025);
FORCEPROP 2 LAST CDS_LIB pure_quanta
J 0
(3950 1875);
DISPLAY INVISIBLE (3950 1875);
FORCEPROP 1 LAST LOCATION C120
J 0
(4000 1975);
DISPLAY 0.702128 (4000 1975);
PAINT YELLOW (4000 1975);
FORCEPROP 1 LASTPIN (3950 1975) $PN 1
J 0
(3960 1955);
DISPLAY 0.787234 (3960 1955);
PAINT MONO (3960 1955);
FORCEPROP 1 LASTPIN (3950 1775) $PN 2
J 0
(3960 1755);
DISPLAY 0.787234 (3960 1755);
PAINT MONO (3960 1755);
FORCEPROP 0 LAST $SEC 1
J 0
(4000 2025);
DISPLAY 0.680851 (4000 2025);
PAINT MONO (4000 2025);
DISPLAY INVISIBLE (4000 2025);
FORCEPROP 0 LAST CDS_SEC 1
J 0
(4000 2025);
DISPLAY 0.680851 (4000 2025);
DISPLAY INVISIBLE (4000 2025);
FORCEADD Q_CAP..1
(4150 1875);
FORCEPROP 1 LAST TOLERANCE 20%
J 0
(4200 1825);
DISPLAY 0.510638 (4200 1825);
PAINT SKYBLUE (4200 1825);
FORCEPROP 1 LAST VALUE 22UF
J 0
(4200 1925);
DISPLAY 0.510638 (4200 1925);
PAINT SKYBLUE (4200 1925);
FORCEPROP 1 LAST VOLTAGE 6.3V
J 0
(4200 1875);
DISPLAY 0.510638 (4200 1875);
PAINT SKYBLUE (4200 1875);
FORCEPROP 1 LAST PACK_TYPE C0603
J 0
(4200 1725);
DISPLAY 0.510638 (4200 1725);
PAINT SKYBLUE (4200 1725);
FORCEPROP 1 LAST MATERIAL X6S
J 0
(4200 1775);
DISPLAY 0.510638 (4200 1775);
PAINT SKYBLUE (4200 1775);
FORCEPROP 1 LAST PART_NUMBER CH6221ME900
J 0
(4200 1725);
DISPLAY 0.510638 (4200 1725);
PAINT WHITE (4200 1725);
DISPLAY INVISIBLE (4200 1725);
FORCEPROP 1 LAST PATH I191
J 0
(4200 2025);
DISPLAY 0.978723 (4200 2025);
PAINT WHITE (4200 2025);
DISPLAY INVISIBLE (4200 2025);
FORCEPROP 2 LAST CDS_LIB pure_quanta
J 0
(4150 1875);
DISPLAY INVISIBLE (4150 1875);
FORCEPROP 1 LAST LOCATION C125
J 0
(4200 1975);
DISPLAY 0.702128 (4200 1975);
PAINT YELLOW (4200 1975);
FORCEPROP 1 LASTPIN (4150 1975) $PN 1
J 0
(4160 1955);
DISPLAY 0.787234 (4160 1955);
PAINT MONO (4160 1955);
FORCEPROP 1 LASTPIN (4150 1775) $PN 2
J 0
(4160 1755);
DISPLAY 0.787234 (4160 1755);
PAINT MONO (4160 1755);
FORCEPROP 0 LAST $SEC 1
J 0
(4200 2025);
DISPLAY 0.680851 (4200 2025);
PAINT MONO (4200 2025);
DISPLAY INVISIBLE (4200 2025);
FORCEPROP 0 LAST CDS_SEC 1
J 0
(4200 2025);
DISPLAY 0.680851 (4200 2025);
DISPLAY INVISIBLE (4200 2025);
FORCEADD Q_CAP..1
(4625 3825);
FORCEPROP 1 LAST VOLTAGE 6.3V
J 0
(4675 3825);
DISPLAY 0.510638 (4675 3825);
PAINT SKYBLUE (4675 3825);
FORCEPROP 1 LAST TOLERANCE 20%
J 0
(4675 3775);
DISPLAY 0.510638 (4675 3775);
PAINT SKYBLUE (4675 3775);
FORCEPROP 1 LAST MATERIAL X6S
J 0
(4675 3725);
DISPLAY 0.510638 (4675 3725);
PAINT SKYBLUE (4675 3725);
FORCEPROP 1 LAST VALUE 22UF
J 0
(4675 3875);
DISPLAY 0.510638 (4675 3875);
PAINT SKYBLUE (4675 3875);
FORCEPROP 1 LAST PACK_TYPE C0603
J 0
(4675 3675);
DISPLAY 0.510638 (4675 3675);
PAINT SKYBLUE (4675 3675);
FORCEPROP 1 LAST PART_NUMBER CH6221ME900
J 0
(4675 3675);
DISPLAY 0.510638 (4675 3675);
PAINT WHITE (4675 3675);
DISPLAY INVISIBLE (4675 3675);
FORCEPROP 1 LAST PATH I192
J 0
(4675 3975);
DISPLAY 0.978723 (4675 3975);
PAINT WHITE (4675 3975);
DISPLAY INVISIBLE (4675 3975);
FORCEPROP 2 LAST CDS_LIB pure_quanta
J 0
(4625 3825);
DISPLAY INVISIBLE (4625 3825);
FORCEPROP 1 LAST LOCATION C131
J 0
(4675 3925);
DISPLAY 0.702128 (4675 3925);
PAINT YELLOW (4675 3925);
FORCEPROP 1 LASTPIN (4625 3925) $PN 1
J 0
(4635 3905);
DISPLAY 0.787234 (4635 3905);
PAINT MONO (4635 3905);
FORCEPROP 1 LASTPIN (4625 3725) $PN 2
J 0
(4635 3705);
DISPLAY 0.787234 (4635 3705);
PAINT MONO (4635 3705);
FORCEPROP 0 LAST $SEC 1
J 0
(4675 3975);
DISPLAY 0.680851 (4675 3975);
PAINT MONO (4675 3975);
DISPLAY INVISIBLE (4675 3975);
FORCEPROP 0 LAST CDS_SEC 1
J 0
(4675 3975);
DISPLAY 0.680851 (4675 3975);
DISPLAY INVISIBLE (4675 3975);
FORCEADD Q_CAP..1
(4825 3825);
FORCEPROP 1 LAST TOLERANCE 20%
J 0
(4875 3775);
DISPLAY 0.510638 (4875 3775);
PAINT SKYBLUE (4875 3775);
FORCEPROP 1 LAST MATERIAL X6S
J 0
(4875 3725);
DISPLAY 0.510638 (4875 3725);
PAINT SKYBLUE (4875 3725);
FORCEPROP 1 LAST PACK_TYPE C0603
J 0
(4875 3675);
DISPLAY 0.510638 (4875 3675);
PAINT SKYBLUE (4875 3675);
FORCEPROP 1 LAST VOLTAGE 6.3V
J 0
(4875 3825);
DISPLAY 0.510638 (4875 3825);
PAINT SKYBLUE (4875 3825);
FORCEPROP 1 LAST VALUE 22UF
J 0
(4875 3875);
DISPLAY 0.510638 (4875 3875);
PAINT SKYBLUE (4875 3875);
FORCEPROP 1 LAST PART_NUMBER CH6221ME900
J 0
(4875 3675);
DISPLAY 0.510638 (4875 3675);
PAINT WHITE (4875 3675);
DISPLAY INVISIBLE (4875 3675);
FORCEPROP 1 LAST PATH I193
J 0
(4875 3975);
DISPLAY 0.978723 (4875 3975);
PAINT WHITE (4875 3975);
DISPLAY INVISIBLE (4875 3975);
FORCEPROP 2 LAST CDS_LIB pure_quanta
J 0
(4825 3825);
DISPLAY INVISIBLE (4825 3825);
FORCEPROP 1 LAST LOCATION C132
J 0
(4875 3925);
DISPLAY 0.702128 (4875 3925);
PAINT YELLOW (4875 3925);
FORCEPROP 1 LASTPIN (4825 3925) $PN 1
J 0
(4835 3905);
DISPLAY 0.787234 (4835 3905);
PAINT MONO (4835 3905);
FORCEPROP 1 LASTPIN (4825 3725) $PN 2
J 0
(4835 3705);
DISPLAY 0.787234 (4835 3705);
PAINT MONO (4835 3705);
FORCEPROP 0 LAST $SEC 1
J 0
(4875 3975);
DISPLAY 0.680851 (4875 3975);
PAINT MONO (4875 3975);
DISPLAY INVISIBLE (4875 3975);
FORCEPROP 0 LAST CDS_SEC 1
J 0
(4875 3975);
DISPLAY 0.680851 (4875 3975);
DISPLAY INVISIBLE (4875 3975);
FORCEADD UNIVERSAL_POWER..1
(-2150 1050);
FORCEPROP 3 LASTPIN (-2150 1000) SIG_NAME P1V2_AUX\g
J 0
(-2140 1010);
DISPLAY 0.659574 (-2140 1010);
PAINT MONO (-2140 1010);
DISPLAY INVISIBLE (-2140 1010);
FORCEPROP 1 LAST HDL_POWER P1V2_AUX
J 1
(-2150 1100);
DISPLAY 0.702128 (-2150 1100);
PAINT GREEN (-2150 1100);
FORCEPROP 1 LAST PATH I21
J 0
(-2100 1075);
DISPLAY 0.872340 (-2100 1075);
PAINT AQUA (-2100 1075);
DISPLAY INVISIBLE (-2100 1075);
FORCEPROP 2 LAST CDS_LIB logical_power
J 0
(-2150 1050);
DISPLAY INVISIBLE (-2150 1050);
FORCEADD UNIVERSAL_POWER..1
(-2450 1700);
FORCEPROP 3 LASTPIN (-2450 1650) SIG_NAME P1V2_AUX\g
J 0
(-2440 1660);
DISPLAY 0.659574 (-2440 1660);
PAINT MONO (-2440 1660);
DISPLAY INVISIBLE (-2440 1660);
FORCEPROP 1 LAST HDL_POWER P1V2_AUX
J 1
(-2450 1750);
DISPLAY 0.702128 (-2450 1750);
PAINT GREEN (-2450 1750);
FORCEPROP 1 LAST PATH I22
J 0
(-2400 1725);
DISPLAY 0.872340 (-2400 1725);
PAINT AQUA (-2400 1725);
DISPLAY INVISIBLE (-2400 1725);
FORCEPROP 2 LAST CDS_LIB logical_power
J 0
(-2450 1700);
DISPLAY INVISIBLE (-2450 1700);
FORCEADD Q_CAP..1
(-2175 1425);
FORCEPROP 1 LAST TOLERANCE 20%
J 0
(-2125 1375);
DISPLAY 0.510638 (-2125 1375);
PAINT SKYBLUE (-2125 1375);
FORCEPROP 1 LAST MATERIAL X6S
J 0
(-2125 1325);
DISPLAY 0.510638 (-2125 1325);
PAINT SKYBLUE (-2125 1325);
FORCEPROP 1 LAST PART_NUMBER CH6221ME900
J 0
(-2150 1200);
DISPLAY 0.510638 (-2150 1200);
PAINT WHITE (-2150 1200);
FORCEPROP 1 LAST VALUE 22UF
J 0
(-2125 1475);
DISPLAY 0.510638 (-2125 1475);
PAINT SKYBLUE (-2125 1475);
FORCEPROP 1 LAST PACK_TYPE C0603
J 0
(-2125 1275);
DISPLAY 0.510638 (-2125 1275);
PAINT SKYBLUE (-2125 1275);
FORCEPROP 1 LAST VOLTAGE 6.3V
J 0
(-2125 1425);
DISPLAY 0.510638 (-2125 1425);
PAINT SKYBLUE (-2125 1425);
FORCEPROP 1 LAST PATH I23
J 0
(-2125 1575);
DISPLAY 0.978723 (-2125 1575);
PAINT WHITE (-2125 1575);
DISPLAY INVISIBLE (-2125 1575);
FORCEPROP 2 LAST CDS_LIB pure_quanta
J 0
(-2175 1425);
DISPLAY INVISIBLE (-2175 1425);
FORCEPROP 1 LAST LOCATION C55
J 0
(-2125 1525);
DISPLAY 0.702128 (-2125 1525);
PAINT YELLOW (-2125 1525);
FORCEPROP 1 LASTPIN (-2175 1525) $PN 1
J 0
(-2165 1505);
DISPLAY 0.808511 (-2165 1505);
PAINT WHITE (-2165 1505);
FORCEPROP 1 LASTPIN (-2175 1325) $PN 2
J 0
(-2165 1305);
DISPLAY 0.808511 (-2165 1305);
PAINT WHITE (-2165 1305);
FORCEPROP 0 LAST $SEC 1
J 0
(-2125 1575);
DISPLAY 0.680851 (-2125 1575);
PAINT MONO (-2125 1575);
DISPLAY INVISIBLE (-2125 1575);
FORCEPROP 0 LAST CDS_SEC 1
J 0
(-2125 1575);
DISPLAY 0.680851 (-2125 1575);
DISPLAY INVISIBLE (-2125 1575);
FORCEADD Q_INDUCTOR..1
(-2050 2275);
FORCEPROP 1 LAST PART_NUMBER CX8PG121009
J 0
(-2300 2200);
DISPLAY 0.510638 (-2300 2200);
PAINT WHITE (-2300 2200);
FORCEPROP 0 LAST VALUE BLM18PG121SN1D/2000MA
J 0
(-2250 2325);
DISPLAY 0.510638 (-2250 2325);
PAINT SKYBLUE (-2250 2325);
FORCEPROP 1 LAST PATH I24
J 0
(-1975 2330);
DISPLAY 0.723404 (-1975 2330);
PAINT GREEN (-1975 2330);
DISPLAY INVISIBLE (-1975 2330);
FORCEPROP 1 LAST MATERIAL IND
J 0
(-2175 2330);
DISPLAY 0.510638 (-2175 2330);
PAINT SKYBLUE (-2175 2330);
DISPLAY INVISIBLE (-2175 2330);
FORCEPROP 0 LAST PACK_TYPE SMLF
J 0
(-2175 2475);
DISPLAY 0.510638 (-2175 2475);
PAINT SKYBLUE (-2175 2475);
DISPLAY INVISIBLE (-2175 2475);
FORCEPROP 2 LAST CDS_LIB pure_quanta
J 0
(-2050 2275);
DISPLAY INVISIBLE (-2050 2275);
FORCEPROP 1 LAST NEEDS_NO_SIZE TRUE
J 0
(-2050 2275);
DISPLAY 0.468085 (-2050 2275);
PAINT GREEN (-2050 2275);
DISPLAY INVISIBLE (-2050 2275);
FORCEPROP 1 LAST LOCATION L10
J 0
(-2275 2250);
DISPLAY 0.702128 (-2275 2250);
PAINT YELLOW (-2275 2250);
FORCEPROP 2 LASTPIN (-2150 2250) $PN 1
J 2
(-2160 2260);
DISPLAY 0.808511 (-2160 2260);
PAINT WHITE (-2160 2260);
FORCEPROP 2 LASTPIN (-1950 2250) $PN 2
J 0
(-1940 2260);
DISPLAY 0.808511 (-1940 2260);
PAINT WHITE (-1940 2260);
FORCEPROP 2 LAST $SEC 1
J 0
(-1975 2375);
DISPLAY 0.680851 (-1975 2375);
PAINT MONO (-1975 2375);
DISPLAY INVISIBLE (-1975 2375);
FORCEPROP 0 LAST CDS_SEC 1
J 0
(-1975 2375);
DISPLAY 0.680851 (-1975 2375);
PAINT MONO (-1975 2375);
DISPLAY INVISIBLE (-1975 2375);
FORCEADD UNIVERSAL_POWER..1
(-3175 2975);
FORCEPROP 3 LASTPIN (-3175 2925) SIG_NAME P1V0_AUX\g
J 0
(-3165 2935);
DISPLAY 0.659574 (-3165 2935);
PAINT MONO (-3165 2935);
DISPLAY INVISIBLE (-3165 2935);
FORCEPROP 1 LAST HDL_POWER P1V0_AUX
J 1
(-3175 3025);
DISPLAY 0.702128 (-3175 3025);
PAINT GREEN (-3175 3025);
FORCEPROP 1 LAST PATH I25
J 0
(-3125 3000);
DISPLAY 0.872340 (-3125 3000);
PAINT AQUA (-3125 3000);
DISPLAY INVISIBLE (-3125 3000);
FORCEPROP 2 LAST CDS_LIB logical_power
J 0
(-3175 2975);
DISPLAY INVISIBLE (-3175 2975);
FORCEADD Q_INDUCTOR..1
(-2750 2900);
FORCEPROP 1 LAST MATERIAL IND
J 0
(-2875 2955);
DISPLAY 0.510638 (-2875 2955);
PAINT SKYBLUE (-2875 2955);
FORCEPROP 1 LAST PART_NUMBER CX8PG121009
J 0
(-2875 3010);
DISPLAY 0.510638 (-2875 3010);
PAINT WHITE (-2875 3010);
FORCEPROP 2 LAST VALUE BLM18PG121SN1D/2000MA
J 0
(-2750 2950);
DISPLAY 0.510638 (-2750 2950);
PAINT SKYBLUE (-2750 2950);
FORCEPROP 2 LAST PACK_TYPE SMLF
J 0
(-2775 3075);
DISPLAY 0.510638 (-2775 3075);
PAINT SKYBLUE (-2775 3075);
FORCEPROP 1 LAST PATH I29
J 0
(-2675 2955);
DISPLAY 0.723404 (-2675 2955);
PAINT GREEN (-2675 2955);
DISPLAY INVISIBLE (-2675 2955);
FORCEPROP 1 LAST NEEDS_NO_SIZE TRUE
J 0
(-2750 2900);
DISPLAY 0.468085 (-2750 2900);
PAINT GREEN (-2750 2900);
DISPLAY INVISIBLE (-2750 2900);
FORCEPROP 2 LAST CDS_LIB pure_quanta
J 0
(-2750 2900);
DISPLAY INVISIBLE (-2750 2900);
FORCEPROP 1 LAST LOCATION L8
J 0
(-3000 2875);
DISPLAY 0.702128 (-3000 2875);
PAINT YELLOW (-3000 2875);
FORCEPROP 2 LASTPIN (-2850 2875) $PN 1
J 2
(-2860 2885);
DISPLAY 0.808511 (-2860 2885);
PAINT WHITE (-2860 2885);
FORCEPROP 2 LASTPIN (-2650 2875) $PN 2
J 0
(-2640 2885);
DISPLAY 0.808511 (-2640 2885);
PAINT WHITE (-2640 2885);
FORCEPROP 2 LAST $SEC 1
J 0
(-2825 3125);
DISPLAY 0.680851 (-2825 3125);
PAINT MONO (-2825 3125);
DISPLAY INVISIBLE (-2825 3125);
FORCEPROP 0 LAST CDS_SEC 1
J 0
(-2825 3125);
DISPLAY 0.680851 (-2825 3125);
PAINT MONO (-2825 3125);
DISPLAY INVISIBLE (-2825 3125);
FORCEADD UNIVERSAL_POWER..1
(-2450 2350);
FORCEPROP 3 LASTPIN (-2450 2300) SIG_NAME P1V8_AUX\g
J 0
(-2440 2310);
DISPLAY 0.659574 (-2440 2310);
PAINT MONO (-2440 2310);
DISPLAY INVISIBLE (-2440 2310);
FORCEPROP 1 LAST HDL_POWER P1V8_AUX
J 1
(-2450 2400);
DISPLAY 0.702128 (-2450 2400);
PAINT GREEN (-2450 2400);
FORCEPROP 1 LAST PATH I30
J 0
(-2400 2375);
DISPLAY 0.872340 (-2400 2375);
PAINT AQUA (-2400 2375);
DISPLAY INVISIBLE (-2400 2375);
FORCEPROP 2 LAST CDS_LIB logical_power
J 0
(-2450 2350);
DISPLAY INVISIBLE (-2450 2350);
FORCEADD Q_CAP..1
(-2500 2700);
FORCEPROP 1 LAST PACK_TYPE C0402
J 0
(-2475 2550);
DISPLAY 0.510638 (-2475 2550);
PAINT SKYBLUE (-2475 2550);
FORCEPROP 1 LAST TOLERANCE 10%
J 0
(-2450 2650);
DISPLAY 0.510638 (-2450 2650);
PAINT SKYBLUE (-2450 2650);
FORCEPROP 1 LAST MATERIAL X6S
J 0
(-2450 2600);
DISPLAY 0.510638 (-2450 2600);
PAINT SKYBLUE (-2450 2600);
FORCEPROP 1 LAST PART_NUMBER CH5104KEB02
J 0
(-2525 2475);
DISPLAY 0.510638 (-2525 2475);
PAINT WHITE (-2525 2475);
FORCEPROP 1 LAST VALUE 1UF
J 0
(-2450 2750);
DISPLAY 0.510638 (-2450 2750);
PAINT SKYBLUE (-2450 2750);
FORCEPROP 1 LAST VOLTAGE 25V
J 0
(-2450 2700);
DISPLAY 0.510638 (-2450 2700);
PAINT SKYBLUE (-2450 2700);
FORCEPROP 1 LAST PATH I31
J 0
(-2450 2850);
DISPLAY 0.978723 (-2450 2850);
PAINT WHITE (-2450 2850);
DISPLAY INVISIBLE (-2450 2850);
FORCEPROP 2 LAST CDS_LIB pure_quanta
J 0
(-2500 2700);
DISPLAY INVISIBLE (-2500 2700);
FORCEPROP 1 LAST LOCATION C52
J 0
(-2450 2800);
DISPLAY 0.702128 (-2450 2800);
PAINT YELLOW (-2450 2800);
FORCEPROP 1 LASTPIN (-2500 2800) $PN 1
J 0
(-2490 2780);
DISPLAY 0.808511 (-2490 2780);
PAINT WHITE (-2490 2780);
FORCEPROP 1 LASTPIN (-2500 2600) $PN 2
J 0
(-2490 2580);
DISPLAY 0.808511 (-2490 2580);
PAINT WHITE (-2490 2580);
FORCEPROP 2 LAST $SEC 1
J 0
(-2450 2900);
DISPLAY 0.680851 (-2450 2900);
PAINT MONO (-2450 2900);
DISPLAY INVISIBLE (-2450 2900);
FORCEPROP 0 LAST CDS_SEC 1
J 0
(-2450 2900);
DISPLAY 0.680851 (-2450 2900);
PAINT MONO (-2450 2900);
DISPLAY INVISIBLE (-2450 2900);
FORCEADD Q_CAP..1
(-2300 2700);
FORCEPROP 1 LAST PACK_TYPE 0402
J 0
(-2250 2550);
DISPLAY 0.510638 (-2250 2550);
PAINT SKYBLUE (-2250 2550);
FORCEPROP 1 LAST VALUE 0.1UF
J 0
(-2250 2750);
DISPLAY 0.510638 (-2250 2750);
PAINT SKYBLUE (-2250 2750);
FORCEPROP 1 LAST TOLERANCE 10%
J 0
(-2250 2650);
DISPLAY 0.510638 (-2250 2650);
PAINT SKYBLUE (-2250 2650);
FORCEPROP 1 LAST MATERIAL X7R
J 0
(-2250 2600);
DISPLAY 0.510638 (-2250 2600);
PAINT SKYBLUE (-2250 2600);
FORCEPROP 1 LAST VOLTAGE 25V
J 0
(-2250 2700);
DISPLAY 0.510638 (-2250 2700);
PAINT SKYBLUE (-2250 2700);
FORCEPROP 1 LAST PATH I32
J 0
(-2250 2850);
DISPLAY 0.978723 (-2250 2850);
PAINT WHITE (-2250 2850);
DISPLAY INVISIBLE (-2250 2850);
FORCEPROP 1 LAST PART_NUMBER CH4104K1B00
J 0
(-2250 2550);
DISPLAY 0.510638 (-2250 2550);
PAINT WHITE (-2250 2550);
DISPLAY INVISIBLE (-2250 2550);
FORCEPROP 2 LAST CDS_LIB pure_quanta
J 0
(-2300 2700);
DISPLAY INVISIBLE (-2300 2700);
FORCEPROP 1 LAST LOCATION C54
J 0
(-2250 2800);
DISPLAY 0.702128 (-2250 2800);
PAINT YELLOW (-2250 2800);
FORCEPROP 1 LASTPIN (-2300 2800) $PN 1
J 0
(-2290 2780);
DISPLAY 0.808511 (-2290 2780);
PAINT WHITE (-2290 2780);
FORCEPROP 1 LASTPIN (-2300 2600) $PN 2
J 0
(-2290 2580);
DISPLAY 0.808511 (-2290 2580);
PAINT WHITE (-2290 2580);
FORCEPROP 2 LAST $SEC 1
J 0
(-2250 2900);
DISPLAY 0.680851 (-2250 2900);
PAINT MONO (-2250 2900);
DISPLAY INVISIBLE (-2250 2900);
FORCEPROP 0 LAST CDS_SEC 1
J 0
(-2250 2900);
DISPLAY 0.680851 (-2250 2900);
PAINT MONO (-2250 2900);
DISPLAY INVISIBLE (-2250 2900);
FORCEADD Q_CAP..1
(-2075 2700);
FORCEPROP 1 LAST VALUE 1UF
J 0
(-2025 2750);
DISPLAY 0.510638 (-2025 2750);
PAINT SKYBLUE (-2025 2750);
FORCEPROP 1 LAST VOLTAGE 25V
J 0
(-2025 2700);
DISPLAY 0.510638 (-2025 2700);
PAINT SKYBLUE (-2025 2700);
FORCEPROP 1 LAST PACK_TYPE C0402
J 0
(-2050 2550);
DISPLAY 0.510638 (-2050 2550);
PAINT SKYBLUE (-2050 2550);
FORCEPROP 1 LAST TOLERANCE 10%
J 0
(-2025 2650);
DISPLAY 0.510638 (-2025 2650);
PAINT SKYBLUE (-2025 2650);
FORCEPROP 1 LAST MATERIAL X6S
J 0
(-2025 2600);
DISPLAY 0.510638 (-2025 2600);
PAINT SKYBLUE (-2025 2600);
FORCEPROP 1 LAST PATH I33
J 0
(-2025 2850);
DISPLAY 0.978723 (-2025 2850);
PAINT WHITE (-2025 2850);
DISPLAY INVISIBLE (-2025 2850);
FORCEPROP 1 LAST PART_NUMBER CH5104KEB02
J 0
(-2025 2550);
DISPLAY 0.510638 (-2025 2550);
PAINT WHITE (-2025 2550);
DISPLAY INVISIBLE (-2025 2550);
FORCEPROP 2 LAST CDS_LIB pure_quanta
J 0
(-2075 2700);
DISPLAY INVISIBLE (-2075 2700);
FORCEPROP 1 LAST LOCATION C56
J 0
(-2025 2800);
DISPLAY 0.702128 (-2025 2800);
PAINT YELLOW (-2025 2800);
FORCEPROP 1 LASTPIN (-2075 2800) $PN 1
J 0
(-2065 2780);
DISPLAY 0.808511 (-2065 2780);
PAINT WHITE (-2065 2780);
FORCEPROP 1 LASTPIN (-2075 2600) $PN 2
J 0
(-2065 2580);
DISPLAY 0.808511 (-2065 2580);
PAINT WHITE (-2065 2580);
FORCEPROP 2 LAST $SEC 1
J 0
(-2025 2900);
DISPLAY 0.680851 (-2025 2900);
PAINT MONO (-2025 2900);
DISPLAY INVISIBLE (-2025 2900);
FORCEPROP 0 LAST CDS_SEC 1
J 0
(-2025 2900);
DISPLAY 0.680851 (-2025 2900);
PAINT MONO (-2025 2900);
DISPLAY INVISIBLE (-2025 2900);
FORCEADD UNIVERSAL_POWER..1
(-775 50);
FORCEPROP 3 LASTPIN (-775 0) SIG_NAME P3V3_P1V8_I2C_I3C\g
J 0
(-765 10);
DISPLAY 0.659574 (-765 10);
PAINT MONO (-765 10);
DISPLAY INVISIBLE (-765 10);
FORCEPROP 1 LAST HDL_POWER P3V3_P1V8_I2C_I3C
J 1
(-775 100);
DISPLAY 0.702128 (-775 100);
PAINT GREEN (-775 100);
FORCEPROP 1 LAST PATH I44
J 0
(-725 75);
DISPLAY 0.872340 (-725 75);
PAINT AQUA (-725 75);
DISPLAY INVISIBLE (-725 75);
FORCEPROP 2 LAST CDS_LIB logical_power
J 0
(-775 50);
DISPLAY INVISIBLE (-775 50);
FORCEADD Q_CAP..1
(-1725 800);
FORCEPROP 1 LAST PACK_TYPE 0402
J 0
(-1675 650);
DISPLAY 0.510638 (-1675 650);
PAINT SKYBLUE (-1675 650);
FORCEPROP 1 LAST TOLERANCE 10%
J 0
(-1675 750);
DISPLAY 0.510638 (-1675 750);
PAINT SKYBLUE (-1675 750);
FORCEPROP 1 LAST MATERIAL X7R
J 0
(-1675 700);
DISPLAY 0.510638 (-1675 700);
PAINT SKYBLUE (-1675 700);
FORCEPROP 1 LAST VOLTAGE 50V
J 0
(-1675 800);
DISPLAY 0.510638 (-1675 800);
PAINT SKYBLUE (-1675 800);
FORCEPROP 1 LAST PART_NUMBER TMP_QCH22206KB16
R 3
J 0
(-1825 950);
DISPLAY 0.510638 (-1825 950);
PAINT WHITE (-1825 950);
FORCEPROP 1 LAST VALUE 2200PF
J 0
(-1700 850);
DISPLAY 0.510638 (-1700 850);
PAINT SKYBLUE (-1700 850);
FORCEPROP 1 LAST PATH I46
J 0
(-1675 950);
DISPLAY 0.978723 (-1675 950);
PAINT WHITE (-1675 950);
DISPLAY INVISIBLE (-1675 950);
FORCEPROP 2 LAST CDS_LIB pure_quanta
J 0
(-1725 800);
DISPLAY INVISIBLE (-1725 800);
FORCEPROP 1 LAST LOCATION C63
J 0
(-1675 900);
DISPLAY 0.702128 (-1675 900);
PAINT YELLOW (-1675 900);
FORCEPROP 1 LASTPIN (-1725 900) $PN 1
J 0
(-1715 880);
DISPLAY 0.808511 (-1715 880);
PAINT WHITE (-1715 880);
FORCEPROP 1 LASTPIN (-1725 700) $PN 2
J 0
(-1715 680);
DISPLAY 0.808511 (-1715 680);
PAINT WHITE (-1715 680);
FORCEPROP 0 LAST $SEC 1
J 0
(-1675 950);
DISPLAY 0.680851 (-1675 950);
PAINT MONO (-1675 950);
DISPLAY INVISIBLE (-1675 950);
FORCEPROP 0 LAST CDS_SEC 1
J 0
(-1675 950);
DISPLAY 0.680851 (-1675 950);
DISPLAY INVISIBLE (-1675 950);
FORCEADD Q_INDUCTOR..1
(-1900 1000);
FORCEPROP 0 LAST VALUE BLM18PG121SN1D/2000MA
J 0
(-2050 1050);
DISPLAY 0.510638 (-2050 1050);
PAINT SKYBLUE (-2050 1050);
FORCEPROP 1 LAST PATH I47
J 0
(-1825 1055);
DISPLAY 0.723404 (-1825 1055);
PAINT GREEN (-1825 1055);
DISPLAY INVISIBLE (-1825 1055);
FORCEPROP 1 LAST MATERIAL IND
J 0
(-2025 1055);
DISPLAY 0.510638 (-2025 1055);
PAINT SKYBLUE (-2025 1055);
DISPLAY INVISIBLE (-2025 1055);
FORCEPROP 1 LAST PART_NUMBER CX8PG121009
J 0
(-2025 1110);
DISPLAY 0.510638 (-2025 1110);
PAINT WHITE (-2025 1110);
DISPLAY INVISIBLE (-2025 1110);
FORCEPROP 0 LAST PACK_TYPE SMLF
J 0
(-2025 1200);
DISPLAY 0.510638 (-2025 1200);
PAINT SKYBLUE (-2025 1200);
DISPLAY INVISIBLE (-2025 1200);
FORCEPROP 1 LAST NEEDS_NO_SIZE TRUE
J 0
(-1900 1000);
DISPLAY 0.468085 (-1900 1000);
PAINT GREEN (-1900 1000);
DISPLAY INVISIBLE (-1900 1000);
FORCEPROP 2 LAST CDS_LIB pure_quanta
J 0
(-1900 1000);
DISPLAY INVISIBLE (-1900 1000);
FORCEPROP 1 LAST LOCATION L11
J 0
(-2125 975);
DISPLAY 0.702128 (-2125 975);
PAINT YELLOW (-2125 975);
FORCEPROP 0 LASTPIN (-2000 975) $PN 1
J 2
(-2010 985);
DISPLAY 0.808511 (-2010 985);
PAINT WHITE (-2010 985);
FORCEPROP 0 LASTPIN (-1800 975) $PN 2
J 0
(-1790 985);
DISPLAY 0.808511 (-1790 985);
PAINT WHITE (-1790 985);
FORCEPROP 0 LAST $SEC 1
J 0
(-1750 1050);
DISPLAY 0.680851 (-1750 1050);
PAINT MONO (-1750 1050);
DISPLAY INVISIBLE (-1750 1050);
FORCEPROP 0 LAST CDS_SEC 1
J 0
(-1750 1050);
DISPLAY 0.680851 (-1750 1050);
DISPLAY INVISIBLE (-1750 1050);
FORCEADD Q_CAP..1
(-1525 800);
FORCEPROP 1 LAST PACK_TYPE C0402
J 0
(-1500 650);
DISPLAY 0.510638 (-1500 650);
PAINT SKYBLUE (-1500 650);
FORCEPROP 1 LAST TOLERANCE 10%
J 0
(-1475 750);
DISPLAY 0.510638 (-1475 750);
PAINT SKYBLUE (-1475 750);
FORCEPROP 1 LAST MATERIAL X6S
J 0
(-1475 700);
DISPLAY 0.510638 (-1475 700);
PAINT SKYBLUE (-1475 700);
FORCEPROP 1 LAST PART_NUMBER CH5104KEB02
J 0
(-1575 575);
DISPLAY 0.510638 (-1575 575);
PAINT WHITE (-1575 575);
FORCEPROP 1 LAST VALUE 1UF
J 0
(-1475 850);
DISPLAY 0.510638 (-1475 850);
PAINT SKYBLUE (-1475 850);
FORCEPROP 1 LAST VOLTAGE 25V
J 0
(-1475 800);
DISPLAY 0.510638 (-1475 800);
PAINT SKYBLUE (-1475 800);
FORCEPROP 1 LAST PATH I48
J 0
(-1475 950);
DISPLAY 0.978723 (-1475 950);
PAINT WHITE (-1475 950);
DISPLAY INVISIBLE (-1475 950);
FORCEPROP 2 LAST CDS_LIB pure_quanta
J 0
(-1525 800);
DISPLAY INVISIBLE (-1525 800);
FORCEPROP 1 LAST LOCATION C67
J 0
(-1475 900);
DISPLAY 0.702128 (-1475 900);
PAINT YELLOW (-1475 900);
FORCEPROP 1 LASTPIN (-1525 900) $PN 1
J 0
(-1515 880);
DISPLAY 0.808511 (-1515 880);
PAINT WHITE (-1515 880);
FORCEPROP 1 LASTPIN (-1525 700) $PN 2
J 0
(-1515 680);
DISPLAY 0.808511 (-1515 680);
PAINT WHITE (-1515 680);
FORCEPROP 2 LAST $SEC 1
J 0
(-1475 1000);
DISPLAY 0.680851 (-1475 1000);
PAINT MONO (-1475 1000);
DISPLAY INVISIBLE (-1475 1000);
FORCEPROP 0 LAST CDS_SEC 1
J 0
(-1475 1000);
DISPLAY 0.680851 (-1475 1000);
PAINT MONO (-1475 1000);
DISPLAY INVISIBLE (-1475 1000);
FORCEADD Q_CAP..1
(-1325 800);
FORCEPROP 1 LAST VALUE 0.1UF
J 0
(-1275 850);
DISPLAY 0.510638 (-1275 850);
PAINT SKYBLUE (-1275 850);
FORCEPROP 1 LAST VOLTAGE 25V
J 0
(-1275 800);
DISPLAY 0.510638 (-1275 800);
PAINT SKYBLUE (-1275 800);
FORCEPROP 1 LAST TOLERANCE 10%
J 0
(-1275 750);
DISPLAY 0.510638 (-1275 750);
PAINT SKYBLUE (-1275 750);
FORCEPROP 1 LAST MATERIAL X7R
J 0
(-1275 700);
DISPLAY 0.510638 (-1275 700);
PAINT SKYBLUE (-1275 700);
FORCEPROP 1 LAST PACK_TYPE 0402
J 0
(-1275 650);
DISPLAY 0.510638 (-1275 650);
PAINT SKYBLUE (-1275 650);
FORCEPROP 1 LAST PATH I49
J 0
(-1275 950);
DISPLAY 0.978723 (-1275 950);
PAINT WHITE (-1275 950);
DISPLAY INVISIBLE (-1275 950);
FORCEPROP 1 LAST PART_NUMBER CH4104K1B00
J 0
(-1275 650);
DISPLAY 0.510638 (-1275 650);
PAINT WHITE (-1275 650);
DISPLAY INVISIBLE (-1275 650);
FORCEPROP 2 LAST CDS_LIB pure_quanta
J 0
(-1325 800);
DISPLAY INVISIBLE (-1325 800);
FORCEPROP 1 LAST LOCATION C71
J 0
(-1275 900);
DISPLAY 0.702128 (-1275 900);
PAINT YELLOW (-1275 900);
FORCEPROP 1 LASTPIN (-1325 900) $PN 1
J 0
(-1315 880);
DISPLAY 0.808511 (-1315 880);
PAINT WHITE (-1315 880);
FORCEPROP 1 LASTPIN (-1325 700) $PN 2
J 0
(-1315 680);
DISPLAY 0.808511 (-1315 680);
PAINT WHITE (-1315 680);
FORCEPROP 2 LAST $SEC 1
J 0
(-1275 1000);
DISPLAY 0.680851 (-1275 1000);
PAINT MONO (-1275 1000);
DISPLAY INVISIBLE (-1275 1000);
FORCEPROP 0 LAST CDS_SEC 1
J 0
(-1275 1000);
DISPLAY 0.680851 (-1275 1000);
PAINT MONO (-1275 1000);
DISPLAY INVISIBLE (-1275 1000);
FORCEADD UNIVERSAL_GND..1
(-1225 525);
FORCEPROP 3 LASTPIN (-1225 575) SIG_NAME GND\g
J 0
(-1215 585);
DISPLAY 0.659574 (-1215 585);
PAINT MONO (-1215 585);
DISPLAY INVISIBLE (-1215 585);
FORCEPROP 1 LAST PATH I50
J 0
(-1150 525);
DISPLAY 0.872340 (-1150 525);
PAINT AQUA (-1150 525);
DISPLAY INVISIBLE (-1150 525);
FORCEPROP 1 LAST HDL_POWER GND
J 1
(-1200 450);
DISPLAY 0.702128 (-1200 450);
PAINT GREEN (-1200 450);
DISPLAY INVISIBLE (-1200 450);
FORCEPROP 2 LAST CDS_LIB logical_power
J 0
(-1225 525);
DISPLAY INVISIBLE (-1225 525);
FORCEADD Q_CAP..1
(-1125 800);
FORCEPROP 1 LAST PACK_TYPE 0402
J 0
(-1075 650);
DISPLAY 0.510638 (-1075 650);
PAINT SKYBLUE (-1075 650);
FORCEPROP 1 LAST VALUE 0.1UF
J 0
(-1075 850);
DISPLAY 0.510638 (-1075 850);
PAINT SKYBLUE (-1075 850);
FORCEPROP 1 LAST TOLERANCE 10%
J 0
(-1075 750);
DISPLAY 0.510638 (-1075 750);
PAINT SKYBLUE (-1075 750);
FORCEPROP 1 LAST MATERIAL X7R
J 0
(-1075 700);
DISPLAY 0.510638 (-1075 700);
PAINT SKYBLUE (-1075 700);
FORCEPROP 1 LAST PART_NUMBER CH4104K1B00
J 0
(-1075 600);
DISPLAY 0.510638 (-1075 600);
PAINT WHITE (-1075 600);
FORCEPROP 1 LAST VOLTAGE 25V
J 0
(-1075 800);
DISPLAY 0.510638 (-1075 800);
PAINT SKYBLUE (-1075 800);
FORCEPROP 1 LAST PATH I51
J 0
(-1075 950);
DISPLAY 0.978723 (-1075 950);
PAINT WHITE (-1075 950);
DISPLAY INVISIBLE (-1075 950);
FORCEPROP 2 LAST CDS_LIB pure_quanta
J 0
(-1125 800);
DISPLAY INVISIBLE (-1125 800);
FORCEPROP 1 LAST LOCATION C73
J 0
(-1075 900);
DISPLAY 0.702128 (-1075 900);
PAINT YELLOW (-1075 900);
FORCEPROP 1 LASTPIN (-1125 900) $PN 1
J 0
(-1115 880);
DISPLAY 0.808511 (-1115 880);
PAINT WHITE (-1115 880);
FORCEPROP 1 LASTPIN (-1125 700) $PN 2
J 0
(-1115 680);
DISPLAY 0.808511 (-1115 680);
PAINT WHITE (-1115 680);
FORCEPROP 2 LAST $SEC 1
J 0
(-1075 1000);
DISPLAY 0.680851 (-1075 1000);
PAINT MONO (-1075 1000);
DISPLAY INVISIBLE (-1075 1000);
FORCEPROP 0 LAST CDS_SEC 1
J 0
(-1075 1000);
DISPLAY 0.680851 (-1075 1000);
PAINT MONO (-1075 1000);
DISPLAY INVISIBLE (-1075 1000);
FORCEADD Q_CAP..1
(-1975 1425);
FORCEPROP 1 LAST PACK_TYPE C0402
J 0
(-1950 1275);
DISPLAY 0.510638 (-1950 1275);
PAINT SKYBLUE (-1950 1275);
FORCEPROP 1 LAST TOLERANCE 10%
J 0
(-1925 1375);
DISPLAY 0.510638 (-1925 1375);
PAINT SKYBLUE (-1925 1375);
FORCEPROP 1 LAST MATERIAL X6S
J 0
(-1925 1325);
DISPLAY 0.510638 (-1925 1325);
PAINT SKYBLUE (-1925 1325);
FORCEPROP 1 LAST VALUE 1UF
J 0
(-1925 1475);
DISPLAY 0.510638 (-1925 1475);
PAINT SKYBLUE (-1925 1475);
FORCEPROP 1 LAST VOLTAGE 25V
J 0
(-1925 1425);
DISPLAY 0.510638 (-1925 1425);
PAINT SKYBLUE (-1925 1425);
FORCEPROP 1 LAST PATH I52
J 0
(-1925 1575);
DISPLAY 0.978723 (-1925 1575);
PAINT WHITE (-1925 1575);
DISPLAY INVISIBLE (-1925 1575);
FORCEPROP 1 LAST PART_NUMBER CH5104KEB02
J 0
(-1925 1275);
DISPLAY 0.510638 (-1925 1275);
PAINT WHITE (-1925 1275);
DISPLAY INVISIBLE (-1925 1275);
FORCEPROP 2 LAST CDS_LIB pure_quanta
J 0
(-1975 1425);
DISPLAY INVISIBLE (-1975 1425);
FORCEPROP 1 LAST LOCATION C58
J 0
(-1925 1525);
DISPLAY 0.702128 (-1925 1525);
PAINT YELLOW (-1925 1525);
FORCEPROP 1 LASTPIN (-1975 1525) $PN 1
J 0
(-1965 1505);
DISPLAY 0.808511 (-1965 1505);
PAINT WHITE (-1965 1505);
FORCEPROP 1 LASTPIN (-1975 1325) $PN 2
J 0
(-1965 1305);
DISPLAY 0.808511 (-1965 1305);
PAINT WHITE (-1965 1305);
FORCEPROP 2 LAST $SEC 1
J 0
(-1925 1625);
DISPLAY 0.680851 (-1925 1625);
PAINT MONO (-1925 1625);
DISPLAY INVISIBLE (-1925 1625);
FORCEPROP 0 LAST CDS_SEC 1
J 0
(-1925 1625);
DISPLAY 0.680851 (-1925 1625);
PAINT MONO (-1925 1625);
DISPLAY INVISIBLE (-1925 1625);
FORCEADD Q_CAP..1
(-1775 1425);
FORCEPROP 1 LAST PACK_TYPE C0402
J 0
(-1750 1275);
DISPLAY 0.510638 (-1750 1275);
PAINT SKYBLUE (-1750 1275);
FORCEPROP 1 LAST TOLERANCE 10%
J 0
(-1725 1375);
DISPLAY 0.510638 (-1725 1375);
PAINT SKYBLUE (-1725 1375);
FORCEPROP 1 LAST MATERIAL X6S
J 0
(-1725 1325);
DISPLAY 0.510638 (-1725 1325);
PAINT SKYBLUE (-1725 1325);
FORCEPROP 1 LAST PART_NUMBER CH5104KEB02
J 0
(-1775 1200);
DISPLAY 0.510638 (-1775 1200);
PAINT WHITE (-1775 1200);
FORCEPROP 1 LAST VALUE 1UF
J 0
(-1725 1475);
DISPLAY 0.510638 (-1725 1475);
PAINT SKYBLUE (-1725 1475);
FORCEPROP 1 LAST VOLTAGE 25V
J 0
(-1725 1425);
DISPLAY 0.510638 (-1725 1425);
PAINT SKYBLUE (-1725 1425);
FORCEPROP 1 LAST PATH I53
J 0
(-1725 1575);
DISPLAY 0.978723 (-1725 1575);
PAINT WHITE (-1725 1575);
DISPLAY INVISIBLE (-1725 1575);
FORCEPROP 2 LAST CDS_LIB pure_quanta
J 0
(-1775 1425);
DISPLAY INVISIBLE (-1775 1425);
FORCEPROP 1 LAST LOCATION C62
J 0
(-1725 1525);
DISPLAY 0.702128 (-1725 1525);
PAINT YELLOW (-1725 1525);
FORCEPROP 1 LASTPIN (-1775 1525) $PN 1
J 0
(-1765 1505);
DISPLAY 0.808511 (-1765 1505);
PAINT WHITE (-1765 1505);
FORCEPROP 1 LASTPIN (-1775 1325) $PN 2
J 0
(-1765 1305);
DISPLAY 0.808511 (-1765 1305);
PAINT WHITE (-1765 1305);
FORCEPROP 2 LAST $SEC 1
J 0
(-1725 1625);
DISPLAY 0.680851 (-1725 1625);
PAINT MONO (-1725 1625);
DISPLAY INVISIBLE (-1725 1625);
FORCEPROP 0 LAST CDS_SEC 1
J 0
(-1725 1625);
DISPLAY 0.680851 (-1725 1625);
PAINT MONO (-1725 1625);
DISPLAY INVISIBLE (-1725 1625);
FORCEADD Q_CAP..1
(-1575 1425);
FORCEPROP 1 LAST VALUE 0.1UF
J 0
(-1525 1475);
DISPLAY 0.510638 (-1525 1475);
PAINT SKYBLUE (-1525 1475);
FORCEPROP 1 LAST VOLTAGE 25V
J 0
(-1525 1425);
DISPLAY 0.510638 (-1525 1425);
PAINT SKYBLUE (-1525 1425);
FORCEPROP 1 LAST TOLERANCE 10%
J 0
(-1525 1375);
DISPLAY 0.510638 (-1525 1375);
PAINT SKYBLUE (-1525 1375);
FORCEPROP 1 LAST MATERIAL X7R
J 0
(-1525 1325);
DISPLAY 0.510638 (-1525 1325);
PAINT SKYBLUE (-1525 1325);
FORCEPROP 1 LAST PACK_TYPE 0402
J 0
(-1525 1275);
DISPLAY 0.510638 (-1525 1275);
PAINT SKYBLUE (-1525 1275);
FORCEPROP 1 LAST PATH I54
J 0
(-1525 1575);
DISPLAY 0.978723 (-1525 1575);
PAINT WHITE (-1525 1575);
DISPLAY INVISIBLE (-1525 1575);
FORCEPROP 1 LAST PART_NUMBER CH4104K1B00
J 0
(-1525 1275);
DISPLAY 0.510638 (-1525 1275);
PAINT WHITE (-1525 1275);
DISPLAY INVISIBLE (-1525 1275);
FORCEPROP 2 LAST CDS_LIB pure_quanta
J 0
(-1575 1425);
DISPLAY INVISIBLE (-1575 1425);
FORCEPROP 1 LAST LOCATION C66
J 0
(-1525 1525);
DISPLAY 0.702128 (-1525 1525);
PAINT YELLOW (-1525 1525);
FORCEPROP 1 LASTPIN (-1575 1525) $PN 1
J 0
(-1565 1505);
DISPLAY 0.808511 (-1565 1505);
PAINT WHITE (-1565 1505);
FORCEPROP 1 LASTPIN (-1575 1325) $PN 2
J 0
(-1565 1305);
DISPLAY 0.808511 (-1565 1305);
PAINT WHITE (-1565 1305);
FORCEPROP 2 LAST $SEC 1
J 0
(-1525 1625);
DISPLAY 0.680851 (-1525 1625);
PAINT MONO (-1525 1625);
DISPLAY INVISIBLE (-1525 1625);
FORCEPROP 0 LAST CDS_SEC 1
J 0
(-1525 1625);
DISPLAY 0.680851 (-1525 1625);
PAINT MONO (-1525 1625);
DISPLAY INVISIBLE (-1525 1625);
FORCEADD Q_CAP..1
(-1825 2075);
FORCEPROP 1 LAST TOLERANCE 10%
J 0
(-1775 2025);
DISPLAY 0.510638 (-1775 2025);
PAINT SKYBLUE (-1775 2025);
FORCEPROP 1 LAST MATERIAL X6S
J 0
(-1775 1975);
DISPLAY 0.510638 (-1775 1975);
PAINT SKYBLUE (-1775 1975);
FORCEPROP 1 LAST VALUE 1UF
J 0
(-1775 2125);
DISPLAY 0.510638 (-1775 2125);
PAINT SKYBLUE (-1775 2125);
FORCEPROP 1 LAST VOLTAGE 25V
J 0
(-1775 2075);
DISPLAY 0.510638 (-1775 2075);
PAINT SKYBLUE (-1775 2075);
FORCEPROP 1 LAST PACK_TYPE C0402
J 0
(-1775 1925);
DISPLAY 0.510638 (-1775 1925);
PAINT SKYBLUE (-1775 1925);
FORCEPROP 1 LAST PART_NUMBER CH5104KEB02
J 0
(-1775 1875);
DISPLAY 0.510638 (-1775 1875);
PAINT WHITE (-1775 1875);
FORCEPROP 1 LAST PATH I55
J 0
(-1775 2225);
DISPLAY 0.978723 (-1775 2225);
PAINT WHITE (-1775 2225);
DISPLAY INVISIBLE (-1775 2225);
FORCEPROP 2 LAST CDS_LIB pure_quanta
J 0
(-1825 2075);
DISPLAY INVISIBLE (-1825 2075);
FORCEPROP 1 LAST LOCATION C61
J 0
(-1775 2175);
DISPLAY 0.702128 (-1775 2175);
PAINT YELLOW (-1775 2175);
FORCEPROP 1 LASTPIN (-1825 2175) $PN 1
J 0
(-1815 2155);
DISPLAY 0.808511 (-1815 2155);
PAINT WHITE (-1815 2155);
FORCEPROP 1 LASTPIN (-1825 1975) $PN 2
J 0
(-1815 1955);
DISPLAY 0.808511 (-1815 1955);
PAINT WHITE (-1815 1955);
FORCEPROP 2 LAST $SEC 1
J 0
(-1775 2275);
DISPLAY 0.680851 (-1775 2275);
PAINT MONO (-1775 2275);
DISPLAY INVISIBLE (-1775 2275);
FORCEPROP 0 LAST CDS_SEC 1
J 0
(-1775 2275);
DISPLAY 0.680851 (-1775 2275);
PAINT MONO (-1775 2275);
DISPLAY INVISIBLE (-1775 2275);
FORCEADD UNIVERSAL_GND..1
(-1625 1775);
FORCEPROP 3 LASTPIN (-1625 1825) SIG_NAME GND\g
J 0
(-1615 1835);
DISPLAY 0.659574 (-1615 1835);
PAINT MONO (-1615 1835);
DISPLAY INVISIBLE (-1615 1835);
FORCEPROP 1 LAST PATH I56
J 0
(-1550 1775);
DISPLAY 0.872340 (-1550 1775);
PAINT AQUA (-1550 1775);
DISPLAY INVISIBLE (-1550 1775);
FORCEPROP 1 LAST HDL_POWER GND
J 1
(-1600 1700);
DISPLAY 0.702128 (-1600 1700);
PAINT GREEN (-1600 1700);
DISPLAY INVISIBLE (-1600 1700);
FORCEPROP 2 LAST CDS_LIB logical_power
J 0
(-1625 1775);
DISPLAY INVISIBLE (-1625 1775);
FORCEADD Q_CAP..1
(-1375 1425);
FORCEPROP 1 LAST PACK_TYPE 0402
J 0
(-1325 1275);
DISPLAY 0.510638 (-1325 1275);
PAINT SKYBLUE (-1325 1275);
FORCEPROP 1 LAST VALUE 0.1UF
J 0
(-1325 1475);
DISPLAY 0.510638 (-1325 1475);
PAINT SKYBLUE (-1325 1475);
FORCEPROP 1 LAST TOLERANCE 10%
J 0
(-1325 1375);
DISPLAY 0.510638 (-1325 1375);
PAINT SKYBLUE (-1325 1375);
FORCEPROP 1 LAST MATERIAL X7R
J 0
(-1325 1325);
DISPLAY 0.510638 (-1325 1325);
PAINT SKYBLUE (-1325 1325);
FORCEPROP 1 LAST VOLTAGE 25V
J 0
(-1325 1425);
DISPLAY 0.510638 (-1325 1425);
PAINT SKYBLUE (-1325 1425);
FORCEPROP 1 LAST PATH I57
J 0
(-1325 1575);
DISPLAY 0.978723 (-1325 1575);
PAINT WHITE (-1325 1575);
DISPLAY INVISIBLE (-1325 1575);
FORCEPROP 1 LAST PART_NUMBER CH4104K1B00
J 0
(-1325 1275);
DISPLAY 0.510638 (-1325 1275);
PAINT WHITE (-1325 1275);
DISPLAY INVISIBLE (-1325 1275);
FORCEPROP 2 LAST CDS_LIB pure_quanta
J 0
(-1375 1425);
DISPLAY INVISIBLE (-1375 1425);
FORCEPROP 1 LAST LOCATION C70
J 0
(-1325 1525);
DISPLAY 0.702128 (-1325 1525);
PAINT YELLOW (-1325 1525);
FORCEPROP 1 LASTPIN (-1375 1525) $PN 1
J 0
(-1365 1505);
DISPLAY 0.808511 (-1365 1505);
PAINT WHITE (-1365 1505);
FORCEPROP 1 LASTPIN (-1375 1325) $PN 2
J 0
(-1365 1305);
DISPLAY 0.808511 (-1365 1305);
PAINT WHITE (-1365 1305);
FORCEPROP 2 LAST $SEC 1
J 0
(-1325 1625);
DISPLAY 0.680851 (-1325 1625);
PAINT MONO (-1325 1625);
DISPLAY INVISIBLE (-1325 1625);
FORCEPROP 0 LAST CDS_SEC 1
J 0
(-1325 1625);
DISPLAY 0.680851 (-1325 1625);
PAINT MONO (-1325 1625);
DISPLAY INVISIBLE (-1325 1625);
FORCEADD Q_CAP..1
(-1175 1425);
FORCEPROP 1 LAST PACK_TYPE 0402
J 0
(-1125 1275);
DISPLAY 0.510638 (-1125 1275);
PAINT SKYBLUE (-1125 1275);
FORCEPROP 1 LAST VALUE 0.1UF
J 0
(-1125 1475);
DISPLAY 0.510638 (-1125 1475);
PAINT SKYBLUE (-1125 1475);
FORCEPROP 1 LAST TOLERANCE 10%
J 0
(-1125 1375);
DISPLAY 0.510638 (-1125 1375);
PAINT SKYBLUE (-1125 1375);
FORCEPROP 1 LAST MATERIAL X7R
J 0
(-1125 1325);
DISPLAY 0.510638 (-1125 1325);
PAINT SKYBLUE (-1125 1325);
FORCEPROP 1 LAST VOLTAGE 25V
J 0
(-1125 1425);
DISPLAY 0.510638 (-1125 1425);
PAINT SKYBLUE (-1125 1425);
FORCEPROP 1 LAST PATH I58
J 0
(-1125 1575);
DISPLAY 0.978723 (-1125 1575);
PAINT WHITE (-1125 1575);
DISPLAY INVISIBLE (-1125 1575);
FORCEPROP 1 LAST PART_NUMBER CH4104K1B00
J 0
(-1125 1275);
DISPLAY 0.510638 (-1125 1275);
PAINT WHITE (-1125 1275);
DISPLAY INVISIBLE (-1125 1275);
FORCEPROP 2 LAST CDS_LIB pure_quanta
J 0
(-1175 1425);
DISPLAY INVISIBLE (-1175 1425);
FORCEPROP 1 LAST LOCATION C72
J 0
(-1125 1525);
DISPLAY 0.702128 (-1125 1525);
PAINT YELLOW (-1125 1525);
FORCEPROP 1 LASTPIN (-1175 1525) $PN 1
J 0
(-1165 1505);
DISPLAY 0.808511 (-1165 1505);
PAINT WHITE (-1165 1505);
FORCEPROP 1 LASTPIN (-1175 1325) $PN 2
J 0
(-1165 1305);
DISPLAY 0.808511 (-1165 1305);
PAINT WHITE (-1165 1305);
FORCEPROP 2 LAST $SEC 1
J 0
(-1125 1625);
DISPLAY 0.680851 (-1125 1625);
PAINT MONO (-1125 1625);
DISPLAY INVISIBLE (-1125 1625);
FORCEPROP 0 LAST CDS_SEC 1
J 0
(-1125 1625);
DISPLAY 0.680851 (-1125 1625);
PAINT MONO (-1125 1625);
DISPLAY INVISIBLE (-1125 1625);
FORCEADD Q_CAP..1
(-1400 2075);
FORCEPROP 1 LAST PACK_TYPE 0402
J 0
(-1350 1925);
DISPLAY 0.510638 (-1350 1925);
PAINT SKYBLUE (-1350 1925);
FORCEPROP 1 LAST VALUE 0.1UF
J 0
(-1350 2125);
DISPLAY 0.510638 (-1350 2125);
PAINT SKYBLUE (-1350 2125);
FORCEPROP 1 LAST TOLERANCE 10%
J 0
(-1350 2025);
DISPLAY 0.510638 (-1350 2025);
PAINT SKYBLUE (-1350 2025);
FORCEPROP 1 LAST MATERIAL X7R
J 0
(-1350 1975);
DISPLAY 0.510638 (-1350 1975);
PAINT SKYBLUE (-1350 1975);
FORCEPROP 1 LAST PART_NUMBER CH4104K1B00
J 0
(-1350 1875);
DISPLAY 0.510638 (-1350 1875);
PAINT WHITE (-1350 1875);
FORCEPROP 1 LAST VOLTAGE 25V
J 0
(-1350 2075);
DISPLAY 0.510638 (-1350 2075);
PAINT SKYBLUE (-1350 2075);
FORCEPROP 1 LAST PATH I59
J 0
(-1350 2225);
DISPLAY 0.978723 (-1350 2225);
PAINT WHITE (-1350 2225);
DISPLAY INVISIBLE (-1350 2225);
FORCEPROP 2 LAST CDS_LIB pure_quanta
J 0
(-1400 2075);
DISPLAY INVISIBLE (-1400 2075);
FORCEPROP 1 LAST LOCATION C69
J 0
(-1350 2175);
DISPLAY 0.702128 (-1350 2175);
PAINT YELLOW (-1350 2175);
FORCEPROP 1 LASTPIN (-1400 2175) $PN 1
J 0
(-1390 2155);
DISPLAY 0.808511 (-1390 2155);
PAINT WHITE (-1390 2155);
FORCEPROP 1 LASTPIN (-1400 1975) $PN 2
J 0
(-1390 1955);
DISPLAY 0.808511 (-1390 1955);
PAINT WHITE (-1390 1955);
FORCEPROP 2 LAST $SEC 1
J 0
(-1350 2275);
DISPLAY 0.680851 (-1350 2275);
PAINT MONO (-1350 2275);
DISPLAY INVISIBLE (-1350 2275);
FORCEPROP 0 LAST CDS_SEC 1
J 0
(-1350 2275);
DISPLAY 0.680851 (-1350 2275);
PAINT MONO (-1350 2275);
DISPLAY INVISIBLE (-1350 2275);
FORCEADD UNIVERSAL_POWER..1
(-600 275);
FORCEPROP 3 LASTPIN (-600 225) SIG_NAME P3V3_P1V8_SD2VDD\g
J 0
(-590 235);
DISPLAY 0.659574 (-590 235);
PAINT MONO (-590 235);
DISPLAY INVISIBLE (-590 235);
FORCEPROP 1 LAST HDL_POWER P3V3_P1V8_SD2VDD
J 1
(-600 325);
DISPLAY 0.702128 (-600 325);
PAINT GREEN (-600 325);
FORCEPROP 1 LAST PATH I60
J 0
(-550 300);
DISPLAY 0.872340 (-550 300);
PAINT AQUA (-550 300);
DISPLAY INVISIBLE (-550 300);
FORCEPROP 2 LAST CDS_LIB logical_power
J 0
(-600 275);
DISPLAY INVISIBLE (-600 275);
FORCEADD UNIVERSAL_POWER..1
(-600 700);
FORCEPROP 3 LASTPIN (-600 650) SIG_NAME P3V3_P2V5_P1V8_RVDD\g
J 0
(-590 660);
DISPLAY 0.659574 (-590 660);
PAINT MONO (-590 660);
DISPLAY INVISIBLE (-590 660);
FORCEPROP 1 LAST HDL_POWER P3V3_P2V5_P1V8_RVDD
J 1
(-600 750);
DISPLAY 0.702128 (-600 750);
PAINT GREEN (-600 750);
FORCEPROP 1 LAST PATH I61
J 0
(-550 725);
DISPLAY 0.872340 (-550 725);
PAINT AQUA (-550 725);
DISPLAY INVISIBLE (-550 725);
FORCEPROP 2 LAST CDS_LIB logical_power
J 0
(-600 700);
DISPLAY INVISIBLE (-600 700);
FORCEADD UNIVERSAL_GND..1
(-875 1150);
FORCEPROP 3 LASTPIN (-875 1200) SIG_NAME GND\g
J 0
(-865 1210);
DISPLAY 0.659574 (-865 1210);
PAINT MONO (-865 1210);
DISPLAY INVISIBLE (-865 1210);
FORCEPROP 1 LAST PATH I62
J 0
(-800 1150);
DISPLAY 0.872340 (-800 1150);
PAINT AQUA (-800 1150);
DISPLAY INVISIBLE (-800 1150);
FORCEPROP 1 LAST HDL_POWER GND
J 1
(-850 1075);
DISPLAY 0.702128 (-850 1075);
PAINT GREEN (-850 1075);
DISPLAY INVISIBLE (-850 1075);
FORCEPROP 2 LAST CDS_LIB logical_power
J 0
(-875 1150);
DISPLAY INVISIBLE (-875 1150);
FORCEADD UNIVERSAL_POWER..1
(-475 450);
FORCEPROP 3 LASTPIN (-475 400) SIG_NAME P3V3_P1V8_SD1VDD\g
J 0
(-465 410);
DISPLAY 0.659574 (-465 410);
PAINT MONO (-465 410);
DISPLAY INVISIBLE (-465 410);
FORCEPROP 1 LAST HDL_POWER P3V3_P1V8_SD1VDD
J 1
(-475 500);
DISPLAY 0.702128 (-475 500);
PAINT GREEN (-475 500);
FORCEPROP 1 LAST PATH I63
J 0
(-425 475);
DISPLAY 0.872340 (-425 475);
PAINT AQUA (-425 475);
DISPLAY INVISIBLE (-425 475);
FORCEPROP 2 LAST CDS_LIB logical_power
J 0
(-475 450);
DISPLAY INVISIBLE (-475 450);
FORCEADD UNIVERSAL_POWER..1
(-450 900);
FORCEPROP 3 LASTPIN (-450 850) SIG_NAME P1V2_P1V0_I3C_VDDL2\g
J 0
(-440 860);
DISPLAY 0.659574 (-440 860);
PAINT MONO (-440 860);
DISPLAY INVISIBLE (-440 860);
FORCEPROP 1 LAST HDL_POWER P1V2_P1V0_I3C_VDDL2
J 1
(-425 950);
DISPLAY 0.702128 (-425 950);
PAINT GREEN (-425 950);
FORCEPROP 1 LAST PATH I64
J 0
(-400 925);
DISPLAY 0.872340 (-400 925);
PAINT AQUA (-400 925);
DISPLAY INVISIBLE (-400 925);
FORCEPROP 2 LAST CDS_LIB logical_power
J 0
(-450 900);
DISPLAY INVISIBLE (-450 900);
FORCEADD UNIVERSAL_POWER..1
(-375 1100);
FORCEPROP 3 LASTPIN (-375 1050) SIG_NAME P1V2_P1V0_I3C_VDDL1\g
J 0
(-365 1060);
DISPLAY 0.659574 (-365 1060);
PAINT MONO (-365 1060);
DISPLAY INVISIBLE (-365 1060);
FORCEPROP 1 LAST HDL_POWER P1V2_P1V0_I3C_VDDL1
J 1
(-375 1150);
DISPLAY 0.702128 (-375 1150);
PAINT GREEN (-375 1150);
FORCEPROP 1 LAST PATH I65
J 0
(-325 1125);
DISPLAY 0.872340 (-325 1125);
PAINT AQUA (-325 1125);
DISPLAY INVISIBLE (-325 1125);
FORCEPROP 2 LAST CDS_LIB logical_power
J 0
(-375 1100);
DISPLAY INVISIBLE (-375 1100);
FORCEADD Q_CAP..1
(-975 1425);
FORCEPROP 1 LAST PACK_TYPE 0402
J 0
(-925 1275);
DISPLAY 0.510638 (-925 1275);
PAINT SKYBLUE (-925 1275);
FORCEPROP 1 LAST VALUE 0.1UF
J 0
(-925 1475);
DISPLAY 0.510638 (-925 1475);
PAINT SKYBLUE (-925 1475);
FORCEPROP 1 LAST TOLERANCE 10%
J 0
(-925 1375);
DISPLAY 0.510638 (-925 1375);
PAINT SKYBLUE (-925 1375);
FORCEPROP 1 LAST MATERIAL X7R
J 0
(-925 1325);
DISPLAY 0.510638 (-925 1325);
PAINT SKYBLUE (-925 1325);
FORCEPROP 1 LAST VOLTAGE 25V
J 0
(-925 1425);
DISPLAY 0.510638 (-925 1425);
PAINT SKYBLUE (-925 1425);
FORCEPROP 1 LAST PATH I66
J 0
(-925 1575);
DISPLAY 0.978723 (-925 1575);
PAINT WHITE (-925 1575);
DISPLAY INVISIBLE (-925 1575);
FORCEPROP 1 LAST PART_NUMBER CH4104K1B00
J 0
(-925 1275);
DISPLAY 0.510638 (-925 1275);
PAINT WHITE (-925 1275);
DISPLAY INVISIBLE (-925 1275);
FORCEPROP 2 LAST CDS_LIB pure_quanta
J 0
(-975 1425);
DISPLAY INVISIBLE (-975 1425);
FORCEPROP 1 LAST LOCATION C74
J 0
(-925 1525);
DISPLAY 0.702128 (-925 1525);
PAINT YELLOW (-925 1525);
FORCEPROP 1 LASTPIN (-975 1525) $PN 1
J 0
(-965 1505);
DISPLAY 0.808511 (-965 1505);
PAINT WHITE (-965 1505);
FORCEPROP 1 LASTPIN (-975 1325) $PN 2
J 0
(-965 1305);
DISPLAY 0.808511 (-965 1305);
PAINT WHITE (-965 1305);
FORCEPROP 2 LAST $SEC 1
J 0
(-925 1625);
DISPLAY 0.680851 (-925 1625);
PAINT MONO (-925 1625);
DISPLAY INVISIBLE (-925 1625);
FORCEPROP 0 LAST CDS_SEC 1
J 0
(-925 1625);
DISPLAY 0.680851 (-925 1625);
PAINT MONO (-925 1625);
DISPLAY INVISIBLE (-925 1625);
FORCEADD OFFPAGE..1
(-700 1700);
FORCEPROP 2 LAST $XR0 17 
J 0
(-921 1700);
DISPLAY 0.638298 (-921 1700);
PAINT MONO (-921 1700);
FORCEPROP 2 LAST PATH I67
J 0
(-900 1750);
DISPLAY 1.021277 (-900 1750);
DISPLAY INVISIBLE (-900 1750);
FORCEPROP 1 LAST COMMENT_BODY TRUE
J 0
(-575 1600);
DISPLAY 0.872340 (-575 1600);
PAINT PEACH (-575 1600);
DISPLAY INVISIBLE (-575 1600);
FORCEPROP 1 LAST OFFPAGE TRUE
J 0
(-375 1575);
DISPLAY 0.872340 (-375 1575);
PAINT GREEN (-375 1575);
DISPLAY INVISIBLE (-375 1575);
FORCEPROP 2 LAST CDS_LIB standard
J 0
(-700 1700);
DISPLAY INVISIBLE (-700 1700);
FORCEADD OFFPAGE..1
(-700 1950);
FORCEPROP 2 LAST $XR0 17 
J 0
(-921 1950);
DISPLAY 0.638298 (-921 1950);
PAINT MONO (-921 1950);
FORCEPROP 2 LAST PATH I68
J 0
(-900 2000);
DISPLAY 1.021277 (-900 2000);
DISPLAY INVISIBLE (-900 2000);
FORCEPROP 1 LAST COMMENT_BODY TRUE
J 0
(-575 1850);
DISPLAY 0.872340 (-575 1850);
PAINT PEACH (-575 1850);
DISPLAY INVISIBLE (-575 1850);
FORCEPROP 1 LAST OFFPAGE TRUE
J 0
(-375 1825);
DISPLAY 0.872340 (-375 1825);
PAINT GREEN (-375 1825);
DISPLAY INVISIBLE (-375 1825);
FORCEPROP 2 LAST CDS_LIB standard
J 0
(-700 1950);
DISPLAY INVISIBLE (-700 1950);
FORCEADD OFFPAGE..1
(-700 1850);
FORCEPROP 2 LAST $XR0 17 
J 0
(-921 1850);
DISPLAY 0.638298 (-921 1850);
PAINT MONO (-921 1850);
FORCEPROP 2 LAST PATH I69
J 0
(-900 1900);
DISPLAY 1.021277 (-900 1900);
DISPLAY INVISIBLE (-900 1900);
FORCEPROP 1 LAST COMMENT_BODY TRUE
J 0
(-575 1750);
DISPLAY 0.872340 (-575 1750);
PAINT PEACH (-575 1750);
DISPLAY INVISIBLE (-575 1750);
FORCEPROP 1 LAST OFFPAGE TRUE
J 0
(-375 1725);
DISPLAY 0.872340 (-375 1725);
PAINT GREEN (-375 1725);
DISPLAY INVISIBLE (-375 1725);
FORCEPROP 2 LAST CDS_LIB standard
J 0
(-700 1850);
DISPLAY INVISIBLE (-700 1850);
FORCEADD OFFPAGE..1
(-700 2250);
FORCEPROP 2 LAST $XR0 17 
J 0
(-921 2250);
DISPLAY 0.638298 (-921 2250);
PAINT MONO (-921 2250);
FORCEPROP 2 LAST PATH I70
J 0
(-900 2300);
DISPLAY 1.021277 (-900 2300);
DISPLAY INVISIBLE (-900 2300);
FORCEPROP 1 LAST COMMENT_BODY TRUE
J 0
(-575 2150);
DISPLAY 0.872340 (-575 2150);
PAINT PEACH (-575 2150);
DISPLAY INVISIBLE (-575 2150);
FORCEPROP 1 LAST OFFPAGE TRUE
J 0
(-375 2125);
DISPLAY 0.872340 (-375 2125);
PAINT GREEN (-375 2125);
DISPLAY INVISIBLE (-375 2125);
FORCEPROP 2 LAST CDS_LIB standard
J 0
(-700 2250);
DISPLAY INVISIBLE (-700 2250);
FORCEADD Q_CAP..1
(-1875 2700);
FORCEPROP 1 LAST VALUE 0.1UF
J 0
(-1825 2750);
DISPLAY 0.510638 (-1825 2750);
PAINT SKYBLUE (-1825 2750);
FORCEPROP 1 LAST TOLERANCE 10%
J 0
(-1825 2650);
DISPLAY 0.510638 (-1825 2650);
PAINT SKYBLUE (-1825 2650);
FORCEPROP 1 LAST MATERIAL X7R
J 0
(-1825 2600);
DISPLAY 0.510638 (-1825 2600);
PAINT SKYBLUE (-1825 2600);
FORCEPROP 1 LAST VOLTAGE 25V
J 0
(-1825 2700);
DISPLAY 0.510638 (-1825 2700);
PAINT SKYBLUE (-1825 2700);
FORCEPROP 1 LAST PACK_TYPE 0402
J 0
(-1825 2550);
DISPLAY 0.510638 (-1825 2550);
PAINT SKYBLUE (-1825 2550);
FORCEPROP 1 LAST PATH I79
J 0
(-1825 2850);
DISPLAY 0.978723 (-1825 2850);
PAINT WHITE (-1825 2850);
DISPLAY INVISIBLE (-1825 2850);
FORCEPROP 1 LAST PART_NUMBER CH4104K1B00
J 0
(-1825 2550);
DISPLAY 0.510638 (-1825 2550);
PAINT WHITE (-1825 2550);
DISPLAY INVISIBLE (-1825 2550);
FORCEPROP 2 LAST CDS_LIB pure_quanta
J 0
(-1875 2700);
DISPLAY INVISIBLE (-1875 2700);
FORCEPROP 1 LAST LOCATION C59
J 0
(-1825 2800);
DISPLAY 0.702128 (-1825 2800);
PAINT YELLOW (-1825 2800);
FORCEPROP 1 LASTPIN (-1875 2800) $PN 1
J 0
(-1865 2780);
DISPLAY 0.808511 (-1865 2780);
PAINT WHITE (-1865 2780);
FORCEPROP 1 LASTPIN (-1875 2600) $PN 2
J 0
(-1865 2580);
DISPLAY 0.808511 (-1865 2580);
PAINT WHITE (-1865 2580);
FORCEPROP 2 LAST $SEC 1
J 0
(-1825 2900);
DISPLAY 0.680851 (-1825 2900);
PAINT MONO (-1825 2900);
DISPLAY INVISIBLE (-1825 2900);
FORCEPROP 0 LAST CDS_SEC 1
J 0
(-1825 2900);
DISPLAY 0.680851 (-1825 2900);
PAINT MONO (-1825 2900);
DISPLAY INVISIBLE (-1825 2900);
FORCEADD UNIVERSAL_GND..1
(-1600 2425);
FORCEPROP 3 LASTPIN (-1600 2475) SIG_NAME GND\g
J 0
(-1590 2485);
DISPLAY 0.659574 (-1590 2485);
PAINT MONO (-1590 2485);
DISPLAY INVISIBLE (-1590 2485);
FORCEPROP 1 LAST PATH I80
J 0
(-1525 2425);
DISPLAY 0.872340 (-1525 2425);
PAINT AQUA (-1525 2425);
DISPLAY INVISIBLE (-1525 2425);
FORCEPROP 1 LAST HDL_POWER GND
J 1
(-1575 2350);
DISPLAY 0.702128 (-1575 2350);
PAINT GREEN (-1575 2350);
DISPLAY INVISIBLE (-1575 2350);
FORCEPROP 2 LAST CDS_LIB logical_power
J 0
(-1600 2425);
DISPLAY INVISIBLE (-1600 2425);
FORCEADD Q_CAP..1
(-1700 2700);
FORCEPROP 1 LAST TOLERANCE 10%
J 0
(-1650 2650);
DISPLAY 0.510638 (-1650 2650);
PAINT SKYBLUE (-1650 2650);
FORCEPROP 1 LAST MATERIAL X6S
J 0
(-1650 2600);
DISPLAY 0.510638 (-1650 2600);
PAINT SKYBLUE (-1650 2600);
FORCEPROP 1 LAST VALUE 1UF
J 0
(-1650 2750);
DISPLAY 0.510638 (-1650 2750);
PAINT SKYBLUE (-1650 2750);
FORCEPROP 1 LAST VOLTAGE 25V
J 0
(-1650 2700);
DISPLAY 0.510638 (-1650 2700);
PAINT SKYBLUE (-1650 2700);
FORCEPROP 1 LAST PACK_TYPE C0402
J 0
(-1675 2550);
DISPLAY 0.510638 (-1675 2550);
PAINT SKYBLUE (-1675 2550);
FORCEPROP 1 LAST PATH I81
J 0
(-1650 2850);
DISPLAY 0.978723 (-1650 2850);
PAINT WHITE (-1650 2850);
DISPLAY INVISIBLE (-1650 2850);
FORCEPROP 1 LAST PART_NUMBER CH5104KEB02
J 0
(-1650 2550);
DISPLAY 0.510638 (-1650 2550);
PAINT WHITE (-1650 2550);
DISPLAY INVISIBLE (-1650 2550);
FORCEPROP 2 LAST CDS_LIB pure_quanta
J 0
(-1700 2700);
DISPLAY INVISIBLE (-1700 2700);
FORCEPROP 1 LAST LOCATION C64
J 0
(-1650 2800);
DISPLAY 0.702128 (-1650 2800);
PAINT YELLOW (-1650 2800);
FORCEPROP 1 LASTPIN (-1700 2800) $PN 1
J 0
(-1690 2780);
DISPLAY 0.808511 (-1690 2780);
PAINT WHITE (-1690 2780);
FORCEPROP 1 LASTPIN (-1700 2600) $PN 2
J 0
(-1690 2580);
DISPLAY 0.808511 (-1690 2580);
PAINT WHITE (-1690 2580);
FORCEPROP 2 LAST $SEC 1
J 0
(-1650 2900);
DISPLAY 0.680851 (-1650 2900);
PAINT MONO (-1650 2900);
DISPLAY INVISIBLE (-1650 2900);
FORCEPROP 0 LAST CDS_SEC 1
J 0
(-1650 2900);
DISPLAY 0.680851 (-1650 2900);
PAINT MONO (-1650 2900);
DISPLAY INVISIBLE (-1650 2900);
FORCEADD Q_CAP..1
(-1500 2700);
FORCEPROP 1 LAST PART_NUMBER CH4104K1B00
J 0
(-1450 2500);
DISPLAY 0.510638 (-1450 2500);
PAINT WHITE (-1450 2500);
FORCEPROP 1 LAST TOLERANCE 10%
J 0
(-1450 2650);
DISPLAY 0.510638 (-1450 2650);
PAINT SKYBLUE (-1450 2650);
FORCEPROP 1 LAST VOLTAGE 25V
J 0
(-1450 2700);
DISPLAY 0.510638 (-1450 2700);
PAINT SKYBLUE (-1450 2700);
FORCEPROP 1 LAST VALUE 0.1UF
J 0
(-1450 2750);
DISPLAY 0.510638 (-1450 2750);
PAINT SKYBLUE (-1450 2750);
FORCEPROP 1 LAST MATERIAL X7R
J 0
(-1450 2600);
DISPLAY 0.510638 (-1450 2600);
PAINT SKYBLUE (-1450 2600);
FORCEPROP 1 LAST PACK_TYPE 0402
J 0
(-1450 2550);
DISPLAY 0.510638 (-1450 2550);
PAINT SKYBLUE (-1450 2550);
FORCEPROP 1 LAST PATH I82
J 0
(-1450 2850);
DISPLAY 0.978723 (-1450 2850);
PAINT WHITE (-1450 2850);
DISPLAY INVISIBLE (-1450 2850);
FORCEPROP 2 LAST CDS_LIB pure_quanta
J 0
(-1500 2700);
DISPLAY INVISIBLE (-1500 2700);
FORCEPROP 1 LAST LOCATION C68
J 0
(-1450 2800);
DISPLAY 0.702128 (-1450 2800);
PAINT YELLOW (-1450 2800);
FORCEPROP 1 LASTPIN (-1500 2800) $PN 1
J 0
(-1490 2780);
DISPLAY 0.808511 (-1490 2780);
PAINT WHITE (-1490 2780);
FORCEPROP 1 LASTPIN (-1500 2600) $PN 2
J 0
(-1490 2580);
DISPLAY 0.808511 (-1490 2580);
PAINT WHITE (-1490 2580);
FORCEPROP 2 LAST $SEC 1
J 0
(-1450 2900);
DISPLAY 0.680851 (-1450 2900);
PAINT MONO (-1450 2900);
DISPLAY INVISIBLE (-1450 2900);
FORCEPROP 0 LAST CDS_SEC 1
J 0
(-1450 2900);
DISPLAY 0.680851 (-1450 2900);
PAINT MONO (-1450 2900);
DISPLAY INVISIBLE (-1450 2900);
FORCEADD UNIVERSAL_GND..1
(-1750 3125);
FORCEPROP 3 LASTPIN (-1750 3175) SIG_NAME GND\g
J 0
(-1740 3185);
DISPLAY 0.659574 (-1740 3185);
PAINT MONO (-1740 3185);
DISPLAY INVISIBLE (-1740 3185);
FORCEPROP 1 LAST PATH I83
J 0
(-1675 3125);
DISPLAY 0.872340 (-1675 3125);
PAINT AQUA (-1675 3125);
DISPLAY INVISIBLE (-1675 3125);
FORCEPROP 1 LAST HDL_POWER GND
J 1
(-1725 3050);
DISPLAY 0.702128 (-1725 3050);
PAINT GREEN (-1725 3050);
DISPLAY INVISIBLE (-1725 3050);
FORCEPROP 2 LAST CDS_LIB logical_power
J 0
(-1750 3125);
DISPLAY INVISIBLE (-1750 3125);
FORCEADD Q_RES..1
(-1450 3600);
FORCEPROP 1 LAST PART_NUMBER CS34992FB05
J 0
(-1725 3525);
DISPLAY 0.510638 (-1725 3525);
PAINT WHITE (-1725 3525);
FORCEPROP 1 LAST MATERIAL CHIP
J 0
(-1150 3550);
DISPLAY 0.510638 (-1150 3550);
PAINT SKYBLUE (-1150 3550);
FORCEPROP 1 LAST VALUE 49.9K
J 2
(-1200 3600);
DISPLAY 0.510638 (-1200 3600);
PAINT SKYBLUE (-1200 3600);
FORCEPROP 1 LAST PACK_TYPE 0402LF
J 0
(-1350 3550);
DISPLAY 0.510638 (-1350 3550);
PAINT SKYBLUE (-1350 3550);
DISPLAY INVISIBLE (-1350 3550);
FORCEPROP 1 LAST WATTAGE 1/16W
J 2
(-850 3550);
DISPLAY 0.510638 (-850 3550);
PAINT SKYBLUE (-850 3550);
DISPLAY INVISIBLE (-850 3550);
FORCEPROP 1 LAST PATH I86
J 0
(-1500 3750);
DISPLAY 0.978723 (-1500 3750);
PAINT WHITE (-1500 3750);
DISPLAY INVISIBLE (-1500 3750);
FORCEPROP 1 LAST TOLERANCE 1%
J 0
(-850 3550);
DISPLAY 0.510638 (-850 3550);
PAINT SKYBLUE (-850 3550);
DISPLAY INVISIBLE (-850 3550);
FORCEPROP 2 LAST CDS_LIB pure_quanta
J 0
(-1450 3600);
DISPLAY INVISIBLE (-1450 3600);
FORCEPROP 1 LAST LOCATION R234
J 0
(-1725 3600);
DISPLAY 0.702128 (-1725 3600);
PAINT YELLOW (-1725 3600);
FORCEPROP 1 LASTPIN (-1550 3600) $PN 1
J 0
(-1538 3612);
DISPLAY 0.808511 (-1538 3612);
PAINT WHITE (-1538 3612);
FORCEPROP 1 LASTPIN (-1350 3600) $PN 2
J 0
(-1388 3612);
DISPLAY 0.808511 (-1388 3612);
PAINT WHITE (-1388 3612);
FORCEPROP 2 LAST $SEC 1
J 0
(-1500 3800);
DISPLAY 0.680851 (-1500 3800);
PAINT MONO (-1500 3800);
DISPLAY INVISIBLE (-1500 3800);
FORCEPROP 0 LAST CDS_SEC 1
J 0
(-1500 3800);
DISPLAY 0.680851 (-1500 3800);
PAINT MONO (-1500 3800);
DISPLAY INVISIBLE (-1500 3800);
FORCEADD Q_RES..1
(-1450 3850);
FORCEPROP 1 LAST PART_NUMBER CS34992FB05
J 0
(-1725 3800);
DISPLAY 0.510638 (-1725 3800);
PAINT WHITE (-1725 3800);
FORCEPROP 1 LAST VALUE 49.9K
J 2
(-1200 3850);
DISPLAY 0.510638 (-1200 3850);
PAINT SKYBLUE (-1200 3850);
FORCEPROP 1 LAST MATERIAL CHIP
J 0
(-1150 3800);
DISPLAY 0.510638 (-1150 3800);
PAINT SKYBLUE (-1150 3800);
FORCEPROP 1 LAST PACK_TYPE 0402LF
J 0
(-1350 3800);
DISPLAY 0.510638 (-1350 3800);
PAINT SKYBLUE (-1350 3800);
DISPLAY INVISIBLE (-1350 3800);
FORCEPROP 1 LAST WATTAGE 1/16W
J 2
(-850 3800);
DISPLAY 0.510638 (-850 3800);
PAINT SKYBLUE (-850 3800);
DISPLAY INVISIBLE (-850 3800);
FORCEPROP 1 LAST PATH I87
J 0
(-1500 4000);
DISPLAY 0.978723 (-1500 4000);
PAINT WHITE (-1500 4000);
DISPLAY INVISIBLE (-1500 4000);
FORCEPROP 1 LAST TOLERANCE 1%
J 0
(-850 3800);
DISPLAY 0.510638 (-850 3800);
PAINT SKYBLUE (-850 3800);
DISPLAY INVISIBLE (-850 3800);
FORCEPROP 2 LAST CDS_LIB pure_quanta
J 0
(-1450 3850);
DISPLAY INVISIBLE (-1450 3850);
FORCEPROP 1 LAST LOCATION R233
J 0
(-1725 3850);
DISPLAY 0.702128 (-1725 3850);
PAINT YELLOW (-1725 3850);
FORCEPROP 1 LASTPIN (-1550 3850) $PN 1
J 0
(-1538 3862);
DISPLAY 0.808511 (-1538 3862);
PAINT WHITE (-1538 3862);
FORCEPROP 1 LASTPIN (-1350 3850) $PN 2
J 0
(-1388 3862);
DISPLAY 0.808511 (-1388 3862);
PAINT WHITE (-1388 3862);
FORCEPROP 2 LAST $SEC 1
J 0
(-1500 4050);
DISPLAY 0.680851 (-1500 4050);
PAINT MONO (-1500 4050);
DISPLAY INVISIBLE (-1500 4050);
FORCEPROP 0 LAST CDS_SEC 1
J 0
(-1500 4050);
DISPLAY 0.680851 (-1500 4050);
PAINT MONO (-1500 4050);
DISPLAY INVISIBLE (-1500 4050);
FORCEADD OFFPAGE..1
(-700 2550);
FORCEPROP 2 LAST $XR0 17 
J 0
(-921 2550);
DISPLAY 0.638298 (-921 2550);
PAINT MONO (-921 2550);
FORCEPROP 2 LAST PATH I88
J 0
(-900 2600);
DISPLAY 1.021277 (-900 2600);
DISPLAY INVISIBLE (-900 2600);
FORCEPROP 1 LAST COMMENT_BODY TRUE
J 0
(-575 2450);
DISPLAY 0.872340 (-575 2450);
PAINT PEACH (-575 2450);
DISPLAY INVISIBLE (-575 2450);
FORCEPROP 1 LAST OFFPAGE TRUE
J 0
(-375 2425);
DISPLAY 0.872340 (-375 2425);
PAINT GREEN (-375 2425);
DISPLAY INVISIBLE (-375 2425);
FORCEPROP 2 LAST CDS_LIB standard
J 0
(-700 2550);
DISPLAY INVISIBLE (-700 2550);
FORCEADD OFFPAGE..1
(-700 2700);
FORCEPROP 2 LAST $XR0 17 
J 0
(-921 2700);
DISPLAY 0.638298 (-921 2700);
PAINT MONO (-921 2700);
FORCEPROP 2 LAST PATH I89
J 0
(-900 2750);
DISPLAY 1.021277 (-900 2750);
DISPLAY INVISIBLE (-900 2750);
FORCEPROP 1 LAST COMMENT_BODY TRUE
J 0
(-575 2600);
DISPLAY 0.872340 (-575 2600);
PAINT PEACH (-575 2600);
DISPLAY INVISIBLE (-575 2600);
FORCEPROP 1 LAST OFFPAGE TRUE
J 0
(-375 2575);
DISPLAY 0.872340 (-375 2575);
PAINT GREEN (-375 2575);
DISPLAY INVISIBLE (-375 2575);
FORCEPROP 2 LAST CDS_LIB standard
J 0
(-700 2700);
DISPLAY INVISIBLE (-700 2700);
FORCEADD OFFPAGE..1
(-525 3400);
FORCEPROP 2 LAST $XR0 17 
J 0
(-746 3400);
DISPLAY 0.638298 (-746 3400);
PAINT MONO (-746 3400);
FORCEPROP 2 LAST PATH I90
J 0
(-725 3450);
DISPLAY 1.021277 (-725 3450);
DISPLAY INVISIBLE (-725 3450);
FORCEPROP 1 LAST COMMENT_BODY TRUE
J 0
(-400 3300);
DISPLAY 0.872340 (-400 3300);
PAINT PEACH (-400 3300);
DISPLAY INVISIBLE (-400 3300);
FORCEPROP 1 LAST OFFPAGE TRUE
J 0
(-200 3275);
DISPLAY 0.872340 (-200 3275);
PAINT GREEN (-200 3275);
DISPLAY INVISIBLE (-200 3275);
FORCEPROP 2 LAST CDS_LIB standard
J 0
(-525 3400);
DISPLAY INVISIBLE (-525 3400);
FORCEADD OFFPAGE..2
R 2
(-525 3700);
FORCEPROP 2 LAST $XR0 17 
J 0
(-749 3700);
DISPLAY 0.638298 (-749 3700);
PAINT MONO (-749 3700);
FORCEPROP 2 LAST PATH I91
J 0
(-775 3750);
DISPLAY 1.021277 (-775 3750);
DISPLAY INVISIBLE (-775 3750);
FORCEPROP 1 LAST COMMENT_BODY TRUE
J 2
(-480 3605);
DISPLAY 0.872340 (-480 3605);
PAINT PEACH (-480 3605);
DISPLAY INVISIBLE (-480 3605);
FORCEPROP 1 LAST OFFPAGE TRUE
J 2
(-850 3575);
DISPLAY 0.872340 (-850 3575);
PAINT GREEN (-850 3575);
DISPLAY INVISIBLE (-850 3575);
FORCEPROP 2 LAST CDS_LIB standard
J 0
(-525 3700);
DISPLAY INVISIBLE (-525 3700);
FORCEADD OFFPAGE..2
R 2
(-525 3650);
FORCEPROP 2 LAST $XR0 17 
J 0
(-749 3650);
DISPLAY 0.638298 (-749 3650);
PAINT MONO (-749 3650);
FORCEPROP 2 LAST PATH I92
J 0
(-775 3700);
DISPLAY 1.021277 (-775 3700);
DISPLAY INVISIBLE (-775 3700);
FORCEPROP 1 LAST COMMENT_BODY TRUE
J 2
(-480 3555);
DISPLAY 0.872340 (-480 3555);
PAINT PEACH (-480 3555);
DISPLAY INVISIBLE (-480 3555);
FORCEPROP 1 LAST OFFPAGE TRUE
J 2
(-850 3525);
DISPLAY 0.872340 (-850 3525);
PAINT GREEN (-850 3525);
DISPLAY INVISIBLE (-850 3525);
FORCEPROP 2 LAST CDS_LIB standard
J 0
(-525 3650);
DISPLAY INVISIBLE (-525 3650);
FORCEADD Q_CAP..1
(-900 4400);
FORCEPROP 1 LAST PART_NUMBER CH5104KEB02
J 0
(-850 4200);
DISPLAY 0.510638 (-850 4200);
PAINT WHITE (-850 4200);
FORCEPROP 1 LAST PACK_TYPE C0402
J 0
(-850 4250);
DISPLAY 0.510638 (-850 4250);
PAINT SKYBLUE (-850 4250);
FORCEPROP 1 LAST MATERIAL X6S
J 0
(-850 4300);
DISPLAY 0.510638 (-850 4300);
PAINT SKYBLUE (-850 4300);
FORCEPROP 1 LAST TOLERANCE 10%
J 0
(-850 4350);
DISPLAY 0.510638 (-850 4350);
PAINT SKYBLUE (-850 4350);
FORCEPROP 1 LAST VOLTAGE 25V
J 0
(-850 4400);
DISPLAY 0.510638 (-850 4400);
PAINT SKYBLUE (-850 4400);
FORCEPROP 1 LAST VALUE 1UF
J 0
(-850 4450);
DISPLAY 0.510638 (-850 4450);
PAINT SKYBLUE (-850 4450);
FORCEPROP 1 LAST PATH I93
J 0
(-850 4550);
DISPLAY 0.978723 (-850 4550);
PAINT WHITE (-850 4550);
DISPLAY INVISIBLE (-850 4550);
FORCEPROP 2 LAST CDS_LIB pure_quanta
J 0
(-900 4400);
DISPLAY INVISIBLE (-900 4400);
FORCEPROP 1 LAST LOCATION C75
J 0
(-850 4500);
DISPLAY 0.702128 (-850 4500);
PAINT YELLOW (-850 4500);
FORCEPROP 1 LASTPIN (-900 4500) $PN 1
J 0
(-890 4480);
DISPLAY 0.808511 (-890 4480);
PAINT WHITE (-890 4480);
FORCEPROP 1 LASTPIN (-900 4300) $PN 2
J 0
(-890 4280);
DISPLAY 0.808511 (-890 4280);
PAINT WHITE (-890 4280);
FORCEPROP 2 LAST $SEC 1
J 0
(-850 4600);
DISPLAY 0.680851 (-850 4600);
PAINT MONO (-850 4600);
DISPLAY INVISIBLE (-850 4600);
FORCEPROP 0 LAST CDS_SEC 1
J 0
(-850 4600);
DISPLAY 0.680851 (-850 4600);
PAINT MONO (-850 4600);
DISPLAY INVISIBLE (-850 4600);
FORCEADD OFFPAGE..2
R 2
(-525 3950);
FORCEPROP 2 LAST $XR0 17 
J 0
(-749 3950);
DISPLAY 0.638298 (-749 3950);
PAINT MONO (-749 3950);
FORCEPROP 2 LAST PATH I94
J 0
(-775 4000);
DISPLAY 1.021277 (-775 4000);
DISPLAY INVISIBLE (-775 4000);
FORCEPROP 1 LAST COMMENT_BODY TRUE
J 2
(-480 3855);
DISPLAY 0.872340 (-480 3855);
PAINT PEACH (-480 3855);
DISPLAY INVISIBLE (-480 3855);
FORCEPROP 1 LAST OFFPAGE TRUE
J 2
(-850 3825);
DISPLAY 0.872340 (-850 3825);
PAINT GREEN (-850 3825);
DISPLAY INVISIBLE (-850 3825);
FORCEPROP 2 LAST CDS_LIB standard
J 0
(-525 3950);
DISPLAY INVISIBLE (-525 3950);
FORCEADD OFFPAGE..2
R 2
(-525 3900);
FORCEPROP 2 LAST $XR0 17 
J 0
(-749 3900);
DISPLAY 0.638298 (-749 3900);
PAINT MONO (-749 3900);
FORCEPROP 2 LAST PATH I95
J 0
(-775 3950);
DISPLAY 1.021277 (-775 3950);
DISPLAY INVISIBLE (-775 3950);
FORCEPROP 1 LAST COMMENT_BODY TRUE
J 2
(-480 3805);
DISPLAY 0.872340 (-480 3805);
PAINT PEACH (-480 3805);
DISPLAY INVISIBLE (-480 3805);
FORCEPROP 1 LAST OFFPAGE TRUE
J 2
(-850 3775);
DISPLAY 0.872340 (-850 3775);
PAINT GREEN (-850 3775);
DISPLAY INVISIBLE (-850 3775);
FORCEPROP 2 LAST CDS_LIB standard
J 0
(-525 3900);
DISPLAY INVISIBLE (-525 3900);
FORCEADD UNIVERSAL_GND..1
(-675 4075);
FORCEPROP 3 LASTPIN (-675 4125) SIG_NAME GND\g
J 0
(-665 4135);
DISPLAY 0.659574 (-665 4135);
PAINT MONO (-665 4135);
DISPLAY INVISIBLE (-665 4135);
FORCEPROP 1 LAST PATH I96
J 0
(-600 4075);
DISPLAY 0.872340 (-600 4075);
PAINT AQUA (-600 4075);
DISPLAY INVISIBLE (-600 4075);
FORCEPROP 1 LAST HDL_POWER GND
J 1
(-650 4000);
DISPLAY 0.702128 (-650 4000);
PAINT GREEN (-650 4000);
DISPLAY INVISIBLE (-650 4000);
FORCEPROP 2 LAST CDS_LIB logical_power
J 0
(-675 4075);
DISPLAY INVISIBLE (-675 4075);
FORCEADD UNIVERSAL_POWER..1
(-1400 4675);
FORCEPROP 3 LASTPIN (-1400 4625) SIG_NAME P3V3_AUX\g
J 0
(-1390 4635);
DISPLAY 0.659574 (-1390 4635);
PAINT MONO (-1390 4635);
DISPLAY INVISIBLE (-1390 4635);
FORCEPROP 1 LAST HDL_POWER P3V3_AUX
J 1
(-1400 4725);
DISPLAY 0.702128 (-1400 4725);
PAINT GREEN (-1400 4725);
FORCEPROP 1 LAST PATH I98
J 0
(-1350 4700);
DISPLAY 0.872340 (-1350 4700);
PAINT AQUA (-1350 4700);
DISPLAY INVISIBLE (-1350 4700);
FORCEPROP 2 LAST CDS_LIB logical_power
J 0
(-1400 4675);
DISPLAY INVISIBLE (-1400 4675);
FORCEADD Q_INDUCTOR..1
(-1100 4625);
FORCEPROP 1 LAST MATERIAL IND
J 0
(-1225 4680);
DISPLAY 0.510638 (-1225 4680);
PAINT SKYBLUE (-1225 4680);
FORCEPROP 1 LAST PART_NUMBER CX8PG121009
J 0
(-1225 4735);
DISPLAY 0.510638 (-1225 4735);
PAINT WHITE (-1225 4735);
FORCEPROP 2 LAST VALUE BLM18PG121SN1D/2000MA
J 0
(-1225 4875);
DISPLAY 0.510638 (-1225 4875);
PAINT SKYBLUE (-1225 4875);
FORCEPROP 2 LAST PACK_TYPE SMLF
J 0
(-1225 4825);
DISPLAY 0.510638 (-1225 4825);
PAINT SKYBLUE (-1225 4825);
FORCEPROP 1 LAST PATH I99
J 0
(-1025 4680);
DISPLAY 0.723404 (-1025 4680);
PAINT GREEN (-1025 4680);
DISPLAY INVISIBLE (-1025 4680);
FORCEPROP 1 LAST NEEDS_NO_SIZE TRUE
J 0
(-1100 4625);
DISPLAY 0.468085 (-1100 4625);
PAINT GREEN (-1100 4625);
DISPLAY INVISIBLE (-1100 4625);
FORCEPROP 2 LAST CDS_LIB pure_quanta
J 0
(-1100 4625);
DISPLAY INVISIBLE (-1100 4625);
FORCEPROP 1 LAST LOCATION L12
J 0
(-1225 4785);
DISPLAY 0.702128 (-1225 4785);
PAINT YELLOW (-1225 4785);
FORCEPROP 2 LASTPIN (-1200 4600) $PN 1
J 2
(-1210 4610);
DISPLAY 0.808511 (-1210 4610);
PAINT WHITE (-1210 4610);
FORCEPROP 2 LASTPIN (-1000 4600) $PN 2
J 0
(-990 4610);
DISPLAY 0.808511 (-990 4610);
PAINT WHITE (-990 4610);
FORCEPROP 2 LAST $SEC 1
J 0
(-1225 4925);
DISPLAY 0.680851 (-1225 4925);
PAINT MONO (-1225 4925);
DISPLAY INVISIBLE (-1225 4925);
FORCEPROP 0 LAST CDS_SEC 1
J 0
(-1225 4925);
DISPLAY 0.680851 (-1225 4925);
PAINT MONO (-1225 4925);
DISPLAY INVISIBLE (-1225 4925);
FORCEADD QUANTA_TITLE_BLOCK_C..1
(5675 -1300);
FORCEPROP 0 LAST CDS_CON_LAST_MODIFIED Fri Aug 25 17:25:38 2023
J 0
(3790 -1285);
DISPLAY INVISIBLE (3790 -1285);
FORCEPROP 2 LAST Q_DEPT 
J 1
(1912 -1251);
DISPLAY 1.957447 (1912 -1251);
PAINT GREEN (1912 -1251);
FORCEPROP 1 LAST CUSTOM_TXT_CDS <CON_LAST_MODIFIED>
J 0
(3790 -1285);
DISPLAY 0.978723 (3790 -1285);
FORCEPROP 2 LAST CUSTOM_TXT_CDS <XR_PAGE_TITLE>
J 0
(-2215 3950);
DISPLAY 0.638298 (-2215 3950);
PAINT PINK (-2215 3950);
DISPLAY INVISIBLE (-2215 3950);
FORCEPROP 1 LAST CUSTOM_TXT_CDS <NAME_2>
J 0
(2500 -1250);
FORCEPROP 1 LAST CUSTOM_TXT_CDS <NAME_1>
J 0
(2500 -1125);
FORCEPROP 1 LAST CUSTOM_TXT_CDS <Q_NUMBER>
J 0
(4272 -1197);
DISPLAY 1.212766 (4272 -1197);
FORCEPROP 1 LAST CUSTOM_TXT_CDS <Q_PROJ>
J 0
(3293 -1198);
DISPLAY 1.212766 (3293 -1198);
FORCEPROP 1 LAST CUSTOM_TXT_CDS <Q_REV>
J 0
(5491 -1197);
DISPLAY 1.212766 (5491 -1197);
FORCEPROP 1 LAST CUSTOM_TXT_CDS <CON_PAGE_NUM> OF <CON_TOTAL_PAGES>
J 0
(5229 -1282);
DISPLAY 0.978723 (5229 -1282);
FORCEPROP 1 LAST Q_TITLE BMC 5
J 0
(-3691 -1274);
DISPLAY 2.446809 (-3691 -1274);
PAINT GREEN (-3691 -1274);
FORCEPROP 1 LAST COMMENT_BODY TRUE
J 0
(5687 -1313);
DISPLAY 0.978723 (5687 -1313);
PAINT PEACH (5687 -1313);
DISPLAY INVISIBLE (5687 -1313);
FORCEPROP 2 LAST CDS_LIB pure_quanta
J 0
(5675 -1300);
DISPLAY INVISIBLE (5675 -1300);
FORCEPROP 1 LAST CDS_LMAN_SYM_OUTLINE -9475,6775,100,-125
J 0
(5675 -1300);
DISPLAY 0.468085 (5675 -1300);
PAINT GREEN (5675 -1300);
DISPLAY INVISIBLE (5675 -1300);
FORCEPROP 2 LAST PAGE_BORDER TRUE
J 0
(-2215 3950);
DISPLAY 0.638298 (-2215 3950);
PAINT PINK (-2215 3950);
DISPLAY INVISIBLE (-2215 3950);
FORCEPROP 2 LAST CDS_XR_PAGE_TITLE CR-16 : @SCM_LIB.SCM(SCH_1):PAGE16
J 0
(-2215 3950);
DISPLAY 0.638298 (-2215 3950);
PAINT PINK (-2215 3950);
DISPLAY INVISIBLE (-2215 3950);
FORCEADD CAD_NOTE..1
(2800 4525);
FORCEPROP 0 LAST L1 POWER CAP DISTRIBUTE ON EACH POWER PIN
J 0
(2750 4325);
DISPLAY 1.021277 (2750 4325);
PAINT WHITE (2750 4325);
FORCEPROP 1 LAST COMMENT_BODY TRUE
J 0
(2825 4625);
DISPLAY 0.978723 (2825 4625);
PAINT PEACH (2825 4625);
DISPLAY INVISIBLE (2825 4625);
FORCEPROP 2 LAST CDS_LIB logical_power
J 0
(2800 4525);
DISPLAY INVISIBLE (2800 4525);
WIRE 16 -1 (3200 300)(3200 325);
WIRE 16 -1 (1975 300)(3200 300);
WIRE 16 -1 (2850 100)(2850 125);
WIRE 16 -1 (2850 100)(2625 100);
WIRE 16 -1 (-775 -50)(-775 0);
WIRE 16 -1 (25 -50)(-775 -50);
WIRE 16 -1 (4250 3375)(4250 3400);
WIRE 16 -1 (4150 3375)(4250 3375);
WIRE 16 -1 (4250 2675)(4250 2700);
WIRE 16 -1 (4150 2675)(4250 2675);
WIRE 16 -1 (4250 2050)(4250 2075);
WIRE 16 -1 (4150 2050)(4250 2050);
WIRE 16 -1 (2775 1450)(2775 1500);
WIRE 16 -1 (2775 1375)(2775 1450);
WIRE 16 -1 (2775 1450)(2625 1450);
WIRE 16 -1 (4275 900)(4275 925);
WIRE 16 -1 (4175 900)(4275 900);
WIRE 16 -1 (4925 4000)(4925 4025);
WIRE 16 -1 (4825 4000)(4925 4000);
WIRE 16 -1 (-2150 1000)(-2150 975);
WIRE 16 -1 (-2450 1650)(-2450 1600);
WIRE 16 -1 (-3175 2925)(-3175 2875);
WIRE 16 -1 (-2450 2300)(-2450 2250);
WIRE 16 -1 (-600 175)(-600 225);
WIRE 16 -1 (-75 175)(-600 175);
WIRE 16 -1 (-600 575)(-600 650);
WIRE 16 -1 (-175 575)(-600 575);
WIRE 16 -1 (-475 375)(-475 400);
WIRE 16 -1 (-125 375)(-475 375);
WIRE 16 -1 (-450 825)(-450 850);
WIRE 16 -1 (-50 825)(-450 825);
WIRE 16 -1 (-375 1000)(-375 1050);
WIRE 16 -1 (-100 1000)(-375 1000);
WIRE 16 -1 (-1400 4625)(-1400 4600);
WIRE 16 -1 (2625 -150)(2625 -200);
WIRE 16 -1 (2775 1175)(2775 1050);
WIRE 16 -1 (4050 1650)(4050 1700);
WIRE 16 -1 (4050 2275)(4050 2325);
WIRE 16 -1 (4050 2975)(4050 3025);
WIRE 16 -1 (4725 3600)(4725 3650);
WIRE 16 -1 (4075 500)(4075 550);
WIRE 16 -1 (-1225 575)(-1225 625);
WIRE 16 -1 (-1625 1825)(-1625 1850);
WIRE 16 -1 (-875 1200)(-875 1250);
WIRE 16 -1 (-1600 2475)(-1600 2525);
WIRE 16 -1 (-1750 3250)(-1750 3175);
WIRE 16 -1 (-1750 3600)(-1750 3250);
WIRE 16 -1 (-1550 3250)(-1750 3250);
WIRE 16 -1 (-675 4125)(-675 4175);
WIRE 16 -1 (275 300)(25 300);
WIRE 16 -1 (275 250)(25 250);
WIRE 16 -1 (25 300)(25 250);
WIRE 16 -1 (25 250)(25 -50);
WIRE 16 -1 (25 450)(275 450);
WIRE 16 -1 (275 400)(25 400);
WIRE 16 -1 (25 450)(25 400);
WIRE 16 -1 (25 400)(-75 400);
WIRE 16 -1 (-75 400)(-75 175);
WIRE 16 -1 (-175 700)(-175 575);
WIRE 16 -1 (275 700)(25 700);
WIRE 16 -1 (25 700)(-175 700);
WIRE 16 -1 (25 750)(25 700);
WIRE 16 -1 (275 750)(25 750);
WIRE 16 -1 (25 750)(25 850);
WIRE 16 -1 (275 850)(25 850);
WIRE 16 -1 (25 900)(25 850);
WIRE 16 -1 (275 900)(25 900);
WIRE 16 -1 (25 600)(275 600);
WIRE 16 -1 (25 550)(275 550);
WIRE 16 -1 (25 600)(25 550);
WIRE 16 -1 (-125 550)(25 550);
WIRE 16 -1 (-125 550)(-125 375);
WIRE 16 -1 (-50 1000)(275 1000);
WIRE 16 -1 (-50 1000)(-50 825);
WIRE 16 -1 (275 1100)(-100 1100);
WIRE 16 -1 (-100 1100)(-100 1000);
WIRE 16 -1 (275 3600)(-1350 3600);
FORCEPROP 2 LAST SIG_NAME A_BMC_ADCREXT1
J 0
(-475 3610);
DISPLAY 0.808511 (-475 3610);
WIRE 16 -1 (275 3550)(-475 3550);
FORCEPROP 2 LAST SIG_NAME ADCVREFEXT1
J 0
(-475 3560);
DISPLAY 0.808511 (-475 3560);
WIRE 16 -1 (275 3250)(-1350 3250);
FORCEPROP 2 LAST SIG_NAME A_BMC_DACREST
J 0
(-475 3260);
DISPLAY 0.808511 (-475 3260);
WIRE 16 -1 (-1550 3600)(-1750 3600);
WIRE 16 -1 (-1750 3850)(-1750 3600);
WIRE 16 -1 (-1550 3850)(-1750 3850);
WIRE 16 -1 (-2500 2875)(-2650 2875);
WIRE 16 -1 (-2500 2800)(-2500 2875);
WIRE 16 -1 (-2300 2800)(-2300 2875);
WIRE 16 -1 (-2300 2875)(-2500 2875);
WIRE 16 -1 (-2075 2800)(-2075 2875);
WIRE 16 -1 (-2075 2875)(-2300 2875);
WIRE 16 -1 (-1875 2875)(-2075 2875);
WIRE 16 -1 (-1875 2800)(-1875 2875);
WIRE 16 -1 (-1700 2875)(-1875 2875);
WIRE 16 -1 (-1700 2800)(-1700 2875);
WIRE 16 -1 (-1500 2875)(-1700 2875);
WIRE 16 -1 (-1500 2800)(-1500 2875);
WIRE 16 -1 (-1050 2875)(-1500 2875);
WIRE 16 -1 (-1050 3100)(-1050 2875);
WIRE 16 -1 (25 3100)(-1050 3100);
FORCEPROP 2 LAST SIG_NAME P1V0_STBY_PLAVDD
J 0
(-485 3110);
DISPLAY 0.808511 (-485 3110);
WIRE 16 -1 (275 3100)(25 3100);
WIRE 16 -1 (275 3000)(25 3000);
WIRE 16 -1 (25 3000)(25 3100);
WIRE 16 -1 (25 3000)(25 2950);
WIRE 16 -1 (275 2950)(25 2950);
WIRE 16 -1 (25 2950)(25 2850);
WIRE 16 -1 (275 2850)(25 2850);
WIRE 16 -1 (25 2850)(25 2800);
WIRE 16 -1 (275 2800)(25 2800);
WIRE 16 -1 (275 2450)(-1175 2450);
FORCEPROP 2 LAST SIG_NAME P1V8_STBY_PE_VCC18A
J 0
(-610 2460);
DISPLAY 0.808511 (-610 2460);
WIRE 16 -1 (-1175 2450)(-1175 2250);
WIRE 16 -1 (-1400 2175)(-1400 2250);
WIRE 16 -1 (-1175 2250)(-1400 2250);
WIRE 16 -1 (-1825 2250)(-1950 2250);
WIRE 16 -1 (-1825 2175)(-1825 2250);
WIRE 16 -1 (-1825 2250)(-1400 2250);
WIRE 16 -1 (275 2150)(-650 2150);
FORCEPROP 2 LAST SIG_NAME P1V8_STBY_RC_VCC18A
J 0
(-610 2160);
DISPLAY 0.808511 (-610 2160);
WIRE 16 -1 (275 1950)(-650 1950);
FORCEPROP 2 LAST SIG_NAME P1V0_STBY_DP_VCC10A
J 0
(-635 1960);
DISPLAY 0.808511 (-635 1960);
WIRE 16 -1 (275 1850)(-650 1850);
FORCEPROP 2 LAST SIG_NAME P1V8_STBY_DP_VCC18A
J 0
(-635 1860);
DISPLAY 0.808511 (-635 1860);
WIRE 16 -1 (1975 450)(2425 450);
WIRE 16 -1 (2425 500)(2425 450);
WIRE 16 -1 (1975 500)(2425 500);
WIRE 16 -1 (2425 550)(2425 500);
WIRE 16 -1 (1975 550)(2425 550);
WIRE 16 -1 (2425 600)(1975 600);
WIRE 16 -1 (2425 600)(2425 550);
WIRE 16 -1 (2425 650)(2425 600);
WIRE 16 -1 (1975 650)(2425 650);
WIRE 16 -1 (2425 700)(2425 650);
WIRE 16 -1 (1975 700)(2425 700);
WIRE 16 -1 (2425 750)(2425 700);
WIRE 16 -1 (1975 750)(2425 750);
WIRE 16 -1 (2425 800)(2425 750);
WIRE 16 -1 (1975 800)(2425 800);
WIRE 16 -1 (2425 850)(1975 850);
WIRE 16 -1 (2425 850)(2425 800);
WIRE 16 -1 (2425 900)(2425 850);
WIRE 16 -1 (1975 900)(2425 900);
WIRE 16 -1 (2425 900)(2850 900);
WIRE 16 -1 (2850 825)(2850 900);
WIRE 16 -1 (2850 900)(3050 900);
WIRE 16 -1 (3050 825)(3050 900);
WIRE 16 -1 (3250 900)(3050 900);
WIRE 16 -1 (3250 825)(3250 900);
WIRE 16 -1 (3250 900)(3425 900);
WIRE 16 -1 (3425 825)(3425 900);
WIRE 16 -1 (3425 900)(3600 900);
WIRE 16 -1 (3600 825)(3600 900);
WIRE 16 -1 (3600 900)(3775 900);
WIRE 16 -1 (3775 825)(3775 900);
WIRE 16 -1 (3775 900)(3975 900);
WIRE 16 -1 (3975 825)(3975 900);
WIRE 16 -1 (3975 900)(4175 900);
WIRE 16 -1 (4175 825)(4175 900);
WIRE 16 -1 (4825 3925)(4825 4000);
WIRE 16 -1 (4625 3925)(4625 4000);
WIRE 16 -1 (4625 4000)(4825 4000);
WIRE 16 -1 (4425 3925)(4425 4000);
WIRE 16 -1 (4425 4000)(4625 4000);
WIRE 16 -1 (4250 3925)(4250 4000);
WIRE 16 -1 (4250 4000)(4425 4000);
WIRE 16 -1 (4075 3925)(4075 4000);
WIRE 16 -1 (4075 4000)(4250 4000);
WIRE 16 -1 (3900 3925)(3900 4000);
WIRE 16 -1 (3900 4000)(4075 4000);
WIRE 16 -1 (3725 3925)(3725 4000);
WIRE 16 -1 (3725 4000)(3900 4000);
WIRE 16 -1 (3525 3925)(3525 4000);
WIRE 16 -1 (3525 4000)(3725 4000);
WIRE 16 -1 (3325 3925)(3325 4000);
WIRE 16 -1 (3325 4000)(3525 4000);
WIRE 16 -1 (3150 3925)(3150 4000);
WIRE 16 -1 (3150 4000)(3325 4000);
WIRE 16 -1 (2950 3925)(2950 4000);
WIRE 16 -1 (2950 4000)(3150 4000);
WIRE 16 -1 (2775 3925)(2775 4000);
WIRE 16 -1 (2775 4000)(2950 4000);
WIRE 16 -1 (2600 3925)(2600 4000);
WIRE 16 -1 (2600 4000)(2775 4000);
WIRE 16 -1 (2425 4000)(1975 4000);
WIRE 16 -1 (2425 4000)(2600 4000);
WIRE 16 -1 (2425 3950)(1975 3950);
WIRE 16 -1 (2425 4000)(2425 3950);
WIRE 16 -1 (2425 3900)(1975 3900);
WIRE 16 -1 (2425 3950)(2425 3900);
WIRE 16 -1 (2425 3850)(1975 3850);
WIRE 16 -1 (2425 3900)(2425 3850);
WIRE 16 -1 (2425 3850)(2425 3800);
WIRE 16 -1 (1975 3800)(2425 3800);
WIRE 16 -1 (2425 3800)(2425 3750);
WIRE 16 -1 (1975 3750)(2425 3750);
WIRE 16 -1 (2425 3700)(1975 3700);
WIRE 16 -1 (2425 3750)(2425 3700);
WIRE 16 -1 (2425 3700)(2425 3650);
WIRE 16 -1 (1975 3650)(2425 3650);
WIRE 16 -1 (2425 3650)(2425 3600);
WIRE 16 -1 (1975 3600)(2425 3600);
WIRE 16 -1 (2425 3550)(1975 3550);
WIRE 16 -1 (2425 3600)(2425 3550);
WIRE 16 -1 (2425 3550)(2425 3500);
WIRE 16 -1 (1975 3500)(2425 3500);
WIRE 16 -1 (2425 3500)(2425 3450);
WIRE 16 -1 (1975 3450)(2425 3450);
WIRE 16 -1 (2425 3450)(2425 3400);
WIRE 16 -1 (1975 3400)(2425 3400);
WIRE 16 -1 (2425 3400)(2425 3350);
WIRE 16 -1 (1975 3350)(2425 3350);
WIRE 16 -1 (2425 3350)(2425 3300);
WIRE 16 -1 (1975 3300)(2425 3300);
WIRE 16 -1 (2425 3300)(2425 3250);
WIRE 16 -1 (1975 3250)(2425 3250);
WIRE 16 -1 (2425 3250)(2425 3200);
WIRE 16 -1 (1975 3200)(2425 3200);
WIRE 16 -1 (2425 3200)(2425 3150);
WIRE 16 -1 (1975 3150)(2425 3150);
WIRE 16 -1 (2425 3150)(2425 3100);
WIRE 16 -1 (1975 3100)(2425 3100);
WIRE 16 -1 (2425 3100)(2425 3050);
WIRE 16 -1 (1975 3050)(2425 3050);
WIRE 16 -1 (4825 3725)(4825 3650);
WIRE 16 -1 (4725 3650)(4825 3650);
WIRE 16 -1 (4625 3650)(4725 3650);
WIRE 16 -1 (4625 3725)(4625 3650);
WIRE 16 -1 (4425 3725)(4425 3650);
WIRE 16 -1 (4425 3650)(4625 3650);
WIRE 16 -1 (4250 3725)(4250 3650);
WIRE 16 -1 (4250 3650)(4425 3650);
WIRE 16 -1 (4075 3725)(4075 3650);
WIRE 16 -1 (4075 3650)(4250 3650);
WIRE 16 -1 (3900 3725)(3900 3650);
WIRE 16 -1 (3900 3650)(4075 3650);
WIRE 16 -1 (3725 3725)(3725 3650);
WIRE 16 -1 (3725 3650)(3900 3650);
WIRE 16 -1 (3525 3725)(3525 3650);
WIRE 16 -1 (3525 3650)(3725 3650);
WIRE 16 -1 (3325 3725)(3325 3650);
WIRE 16 -1 (3325 3650)(3525 3650);
WIRE 16 -1 (3150 3725)(3150 3650);
WIRE 16 -1 (3150 3650)(3325 3650);
WIRE 16 -1 (2950 3725)(2950 3650);
WIRE 16 -1 (2950 3650)(3150 3650);
WIRE 16 -1 (2775 3725)(2775 3650);
WIRE 16 -1 (2775 3650)(2950 3650);
WIRE 16 -1 (2600 3650)(2775 3650);
WIRE 16 -1 (2600 3725)(2600 3650);
WIRE 16 -1 (1975 2500)(2425 2500);
WIRE 16 -1 (2425 2550)(2425 2500);
WIRE 16 -1 (1975 2550)(2425 2550);
WIRE 16 -1 (2425 2600)(2425 2550);
WIRE 16 -1 (1975 2600)(2425 2600);
WIRE 16 -1 (2425 2650)(2425 2600);
WIRE 16 -1 (1975 2650)(2425 2650);
WIRE 16 -1 (2425 2700)(2425 2650);
WIRE 16 -1 (1975 2700)(2425 2700);
WIRE 16 -1 (2425 2750)(2425 2700);
WIRE 16 -1 (1975 2750)(2425 2750);
WIRE 16 -1 (2425 2800)(2425 2750);
WIRE 16 -1 (1975 2800)(2425 2800);
WIRE 16 -1 (2425 2850)(2425 2800);
WIRE 16 -1 (1975 2850)(2425 2850);
WIRE 16 -1 (2425 2900)(2425 2850);
WIRE 16 -1 (1975 2900)(2425 2900);
WIRE 16 -1 (2425 2900)(2425 2950);
WIRE 16 -1 (1975 2950)(2425 2950);
WIRE 16 -1 (2425 2950)(2625 2950);
WIRE 16 -1 (2625 2950)(2625 3375);
WIRE 16 -1 (2625 3375)(2825 3375);
WIRE 16 -1 (2825 3300)(2825 3375);
WIRE 16 -1 (2825 3375)(3025 3375);
WIRE 16 -1 (3025 3300)(3025 3375);
WIRE 16 -1 (3225 3375)(3025 3375);
WIRE 16 -1 (3225 3300)(3225 3375);
WIRE 16 -1 (3225 3375)(3400 3375);
WIRE 16 -1 (3400 3300)(3400 3375);
WIRE 16 -1 (3400 3375)(3575 3375);
WIRE 16 -1 (3575 3300)(3575 3375);
WIRE 16 -1 (3575 3375)(3750 3375);
WIRE 16 -1 (3750 3300)(3750 3375);
WIRE 16 -1 (3750 3375)(3950 3375);
WIRE 16 -1 (3950 3300)(3950 3375);
WIRE 16 -1 (3950 3375)(4150 3375);
WIRE 16 -1 (4150 3300)(4150 3375);
WIRE 16 -1 (4150 3100)(4150 3025);
WIRE 16 -1 (4050 3025)(4150 3025);
WIRE 16 -1 (3950 3025)(4050 3025);
WIRE 16 -1 (3950 3100)(3950 3025);
WIRE 16 -1 (3750 3025)(3950 3025);
WIRE 16 -1 (3750 3100)(3750 3025);
WIRE 16 -1 (3575 3025)(3750 3025);
WIRE 16 -1 (3575 3100)(3575 3025);
WIRE 16 -1 (3400 3025)(3575 3025);
WIRE 16 -1 (3400 3100)(3400 3025);
WIRE 16 -1 (3225 3025)(3400 3025);
WIRE 16 -1 (3225 3100)(3225 3025);
WIRE 16 -1 (3025 3100)(3025 3025);
WIRE 16 -1 (3225 3025)(3025 3025);
WIRE 16 -1 (2825 3025)(3025 3025);
WIRE 16 -1 (2825 3100)(2825 3025);
WIRE 16 -1 (1975 1850)(2425 1850);
WIRE 16 -1 (2425 1900)(2425 1850);
WIRE 16 -1 (1975 1900)(2425 1900);
WIRE 16 -1 (2425 2000)(2425 1900);
WIRE 16 -1 (1975 2000)(2425 2000);
WIRE 16 -1 (2425 2050)(1975 2050);
WIRE 16 -1 (2425 2050)(2425 2000);
WIRE 16 -1 (2425 2100)(2425 2050);
WIRE 16 -1 (1975 2100)(2425 2100);
WIRE 16 -1 (2425 2150)(2425 2100);
WIRE 16 -1 (1975 2150)(2425 2150);
WIRE 16 -1 (2425 2200)(2425 2150);
WIRE 16 -1 (1975 2200)(2425 2200);
WIRE 16 -1 (2425 2250)(2425 2200);
WIRE 16 -1 (1975 2250)(2425 2250);
WIRE 16 -1 (2425 2300)(2425 2250);
WIRE 16 -1 (1975 2300)(2425 2300);
WIRE 16 -1 (2425 2300)(2625 2300);
WIRE 16 -1 (2625 2300)(2625 2675);
WIRE 16 -1 (2625 2675)(2825 2675);
WIRE 16 -1 (2825 2600)(2825 2675);
WIRE 16 -1 (2825 2675)(3025 2675);
WIRE 16 -1 (3025 2600)(3025 2675);
WIRE 16 -1 (3225 2675)(3025 2675);
WIRE 16 -1 (3225 2600)(3225 2675);
WIRE 16 -1 (3225 2675)(3400 2675);
WIRE 16 -1 (3400 2600)(3400 2675);
WIRE 16 -1 (3400 2675)(3575 2675);
WIRE 16 -1 (3575 2600)(3575 2675);
WIRE 16 -1 (3575 2675)(3750 2675);
WIRE 16 -1 (3750 2600)(3750 2675);
WIRE 16 -1 (3750 2675)(3950 2675);
WIRE 16 -1 (3950 2600)(3950 2675);
WIRE 16 -1 (3950 2675)(4150 2675);
WIRE 16 -1 (4150 2600)(4150 2675);
WIRE 16 -1 (4150 2400)(4150 2325);
WIRE 16 -1 (4050 2325)(4150 2325);
WIRE 16 -1 (3950 2400)(3950 2325);
WIRE 16 -1 (3950 2325)(4050 2325);
WIRE 16 -1 (3750 2400)(3750 2325);
WIRE 16 -1 (3750 2325)(3950 2325);
WIRE 16 -1 (3575 2400)(3575 2325);
WIRE 16 -1 (3575 2325)(3750 2325);
WIRE 16 -1 (3400 2400)(3400 2325);
WIRE 16 -1 (3400 2325)(3575 2325);
WIRE 16 -1 (3225 2400)(3225 2325);
WIRE 16 -1 (3225 2325)(3400 2325);
WIRE 16 -1 (3025 2400)(3025 2325);
WIRE 16 -1 (3225 2325)(3025 2325);
WIRE 16 -1 (2825 2325)(3025 2325);
WIRE 16 -1 (2825 2400)(2825 2325);
WIRE 16 -1 (1975 1200)(2425 1200);
WIRE 16 -1 (2425 1250)(2425 1200);
WIRE 16 -1 (1975 1250)(2425 1250);
WIRE 16 -1 (2425 1300)(1975 1300);
WIRE 16 -1 (2425 1300)(2425 1250);
WIRE 16 -1 (2425 1350)(1975 1350);
WIRE 16 -1 (2425 1350)(2425 1300);
WIRE 16 -1 (2425 1400)(2425 1350);
WIRE 16 -1 (1975 1400)(2425 1400);
WIRE 16 -1 (2425 1450)(2425 1400);
WIRE 16 -1 (1975 1450)(2425 1450);
WIRE 16 -1 (2425 1500)(2425 1450);
WIRE 16 -1 (1975 1500)(2425 1500);
WIRE 16 -1 (2425 1550)(2425 1500);
WIRE 16 -1 (1975 1550)(2425 1550);
WIRE 16 -1 (2425 1550)(2425 1600);
WIRE 16 -1 (1975 1600)(2425 1600);
WIRE 16 -1 (2425 1650)(2425 1600);
WIRE 16 -1 (1975 1650)(2425 1650);
WIRE 16 -1 (2425 1700)(2425 1650);
WIRE 16 -1 (1975 1700)(2425 1700);
WIRE 16 -1 (2625 1700)(2425 1700);
WIRE 16 -1 (2625 2050)(2625 1700);
WIRE 16 -1 (2825 2050)(2825 1975);
WIRE 16 -1 (2625 2050)(2825 2050);
WIRE 16 -1 (2825 2050)(3025 2050);
WIRE 16 -1 (3025 1975)(3025 2050);
WIRE 16 -1 (3225 2050)(3025 2050);
WIRE 16 -1 (3225 1975)(3225 2050);
WIRE 16 -1 (3225 2050)(3575 2050);
WIRE 16 -1 (3575 1975)(3575 2050);
WIRE 16 -1 (3575 2050)(3750 2050);
WIRE 16 -1 (3750 1975)(3750 2050);
WIRE 16 -1 (3750 2050)(3950 2050);
WIRE 16 -1 (3950 1975)(3950 2050);
WIRE 16 -1 (3950 2050)(4150 2050);
WIRE 16 -1 (4150 1975)(4150 2050);
WIRE 16 -1 (2825 1775)(2825 1700);
WIRE 16 -1 (2825 1700)(3025 1700);
WIRE 16 -1 (3025 1775)(3025 1700);
WIRE 16 -1 (3225 1700)(3025 1700);
WIRE 16 -1 (3225 1775)(3225 1700);
WIRE 16 -1 (3575 1700)(3225 1700);
WIRE 16 -1 (3575 1775)(3575 1700);
WIRE 16 -1 (3575 1700)(3750 1700);
WIRE 16 -1 (3750 1775)(3750 1700);
WIRE 16 -1 (3750 1700)(3950 1700);
WIRE 16 -1 (3950 1775)(3950 1700);
WIRE 16 -1 (3950 1700)(4050 1700);
WIRE 16 -1 (4050 1700)(4150 1700);
WIRE 16 -1 (4150 1775)(4150 1700);
WIRE 16 -1 (4175 625)(4175 550);
WIRE 16 -1 (4075 550)(4175 550);
WIRE 16 -1 (3975 550)(4075 550);
WIRE 16 -1 (3975 625)(3975 550);
WIRE 16 -1 (3775 625)(3775 550);
WIRE 16 -1 (3775 550)(3975 550);
WIRE 16 -1 (3600 625)(3600 550);
WIRE 16 -1 (3600 550)(3775 550);
WIRE 16 -1 (3425 625)(3425 550);
WIRE 16 -1 (3425 550)(3600 550);
WIRE 16 -1 (3250 625)(3250 550);
WIRE 16 -1 (3250 550)(3425 550);
WIRE 16 -1 (3050 625)(3050 550);
WIRE 16 -1 (3250 550)(3050 550);
WIRE 16 -1 (2850 550)(3050 550);
WIRE 16 -1 (2850 625)(2850 550);
WIRE 16 -1 (1975 200)(2425 200);
WIRE 16 -1 (2425 200)(2425 100);
WIRE 16 -1 (2425 100)(2625 100);
WIRE 16 -1 (2625 50)(2625 100);
WIRE 16 -1 (-1725 700)(-1725 625);
WIRE 16 -1 (-1725 625)(-1525 625);
WIRE 16 -1 (-1525 700)(-1525 625);
WIRE 16 -1 (-1325 625)(-1525 625);
WIRE 16 -1 (-1325 700)(-1325 625);
WIRE 16 -1 (-1225 625)(-1325 625);
WIRE 16 -1 (-1125 625)(-1225 625);
WIRE 16 -1 (-1125 700)(-1125 625);
WIRE 16 -1 (275 1200)(-750 1200);
FORCEPROP 2 LAST SIG_NAME P1V2_STBY_MVDD_CK
J 0
(-635 1210);
DISPLAY 0.808511 (-635 1210);
WIRE 16 -1 (-750 1200)(-750 975);
WIRE 16 -1 (-1125 900)(-1125 975);
WIRE 16 -1 (-750 975)(-1125 975);
WIRE 16 -1 (-1325 900)(-1325 975);
WIRE 16 -1 (-1125 975)(-1325 975);
WIRE 16 -1 (-1525 900)(-1525 975);
WIRE 16 -1 (-1325 975)(-1525 975);
WIRE 16 -1 (-1725 975)(-1800 975);
WIRE 16 -1 (-1725 900)(-1725 975);
WIRE 16 -1 (-1725 975)(-1525 975);
WIRE 16 -1 (-2175 1325)(-2175 1250);
WIRE 16 -1 (-2175 1250)(-1975 1250);
WIRE 16 -1 (-1975 1325)(-1975 1250);
WIRE 16 -1 (-1975 1250)(-1775 1250);
WIRE 16 -1 (-1775 1325)(-1775 1250);
WIRE 16 -1 (-1775 1250)(-1575 1250);
WIRE 16 -1 (-1575 1325)(-1575 1250);
WIRE 16 -1 (-1375 1250)(-1575 1250);
WIRE 16 -1 (-1375 1325)(-1375 1250);
WIRE 16 -1 (-1175 1250)(-1375 1250);
WIRE 16 -1 (-1175 1325)(-1175 1250);
WIRE 16 -1 (-975 1250)(-1175 1250);
WIRE 16 -1 (-975 1325)(-975 1250);
WIRE 16 -1 (-875 1250)(-975 1250);
WIRE 16 -1 (-775 1250)(-875 1250);
WIRE 16 -1 (-775 1325)(-775 1250);
WIRE 16 -1 (25 1250)(275 1250);
WIRE 16 -1 (25 1300)(25 1250);
WIRE 16 -1 (275 1300)(25 1300);
WIRE 16 -1 (25 1350)(25 1300);
WIRE 16 -1 (275 1350)(25 1350);
WIRE 16 -1 (25 1400)(25 1350);
WIRE 16 -1 (275 1400)(25 1400);
WIRE 16 -1 (25 1450)(25 1400);
WIRE 16 -1 (275 1450)(25 1450);
WIRE 16 -1 (25 1500)(25 1450);
WIRE 16 -1 (275 1500)(25 1500);
WIRE 16 -1 (25 1550)(25 1500);
WIRE 16 -1 (275 1550)(25 1550);
WIRE 16 -1 (25 1550)(25 1600);
WIRE 16 -1 (275 1600)(25 1600);
WIRE 16 -1 (-775 1600)(25 1600);
WIRE 16 -1 (-775 1525)(-775 1600);
WIRE 16 -1 (-975 1525)(-975 1600);
WIRE 16 -1 (-775 1600)(-975 1600);
WIRE 16 -1 (-975 1600)(-1175 1600);
WIRE 16 -1 (-1175 1525)(-1175 1600);
WIRE 16 -1 (-1375 1525)(-1375 1600);
WIRE 16 -1 (-1175 1600)(-1375 1600);
WIRE 16 -1 (-1375 1600)(-1575 1600);
WIRE 16 -1 (-1575 1525)(-1575 1600);
WIRE 16 -1 (-1575 1600)(-1775 1600);
WIRE 16 -1 (-1775 1525)(-1775 1600);
WIRE 16 -1 (-1975 1525)(-1975 1600);
WIRE 16 -1 (-1775 1600)(-1975 1600);
WIRE 16 -1 (-1975 1600)(-2175 1600);
WIRE 16 -1 (-2175 1525)(-2175 1600);
WIRE 16 -1 (-2175 1600)(-2450 1600);
WIRE 16 -1 (-1825 1975)(-1825 1850);
WIRE 16 -1 (-1825 1850)(-1625 1850);
WIRE 16 -1 (-1400 1850)(-1625 1850);
WIRE 16 -1 (-1400 1975)(-1400 1850);
WIRE 16 -1 (-2500 2600)(-2500 2525);
WIRE 16 -1 (-2500 2525)(-2300 2525);
WIRE 16 -1 (-2300 2600)(-2300 2525);
WIRE 16 -1 (-2300 2525)(-2075 2525);
WIRE 16 -1 (-2075 2600)(-2075 2525);
WIRE 16 -1 (-2075 2525)(-1875 2525);
WIRE 16 -1 (-1875 2600)(-1875 2525);
WIRE 16 -1 (-1875 2525)(-1700 2525);
WIRE 16 -1 (-1700 2600)(-1700 2525);
WIRE 16 -1 (-1700 2525)(-1600 2525);
WIRE 16 -1 (-1600 2525)(-1500 2525);
WIRE 16 -1 (-1500 2600)(-1500 2525);
WIRE 16 -1 (275 3850)(-1350 3850);
FORCEPROP 2 LAST SIG_NAME A_BMC_ADCREXT0
J 0
(-475 3860);
DISPLAY 0.808511 (-475 3860);
WIRE 16 -1 (275 3350)(25 3350);
WIRE 16 -1 (25 3400)(-475 3400);
FORCEPROP 2 LAST SIG_NAME P3V3_STBY_DACAV33
J 0
(-475 3410);
DISPLAY 0.808511 (-475 3410);
WIRE 16 -1 (25 3400)(25 3350);
WIRE 16 -1 (275 3400)(25 3400);
WIRE 16 -1 (-900 4500)(-900 4600);
WIRE 16 -1 (-900 4600)(-1000 4600);
WIRE 16 -1 (-425 4600)(-900 4600);
WIRE 16 -1 (-425 4525)(-425 4600);
WIRE 16 -1 (50 4600)(-425 4600);
FORCEPROP 2 LAST SIG_NAME A_BMC_ADCAV33
J 0
(-385 4610);
DISPLAY 0.808511 (-385 4610);
WIRE 16 -1 (50 4600)(50 4100);
WIRE 16 -1 (275 4100)(50 4100);
WIRE 16 -1 (50 4100)(50 4050);
WIRE 16 -1 (275 4050)(50 4050);
WIRE 16 -1 (-900 4300)(-900 4175);
WIRE 16 -1 (-675 4175)(-900 4175);
WIRE 16 -1 (-425 4175)(-675 4175);
WIRE 16 -1 (-425 4325)(-425 4175);
WIRE 16 -1 (-475 3800)(275 3800);
FORCEPROP 2 LAST SIG_NAME ADCVREFEXT0
J 0
(-475 3810);
DISPLAY 0.808511 (-475 3810);
WIRE 16 -1 (275 2250)(-650 2250);
FORCEPROP 2 LAST SIG_NAME P1V0_STBY_RC_VCC10A
J 0
(-610 2260);
DISPLAY 0.808511 (-610 2260);
WIRE 16 -1 (275 2550)(-650 2550);
FORCEPROP 2 LAST SIG_NAME P1V0_STBY_PE_VCC10A
J 0
(-610 2560);
DISPLAY 0.808511 (-610 2560);
WIRE 16 -1 (275 1700)(-650 1700);
FORCEPROP 2 LAST SIG_NAME P1V8_STBY_AVDDPLL
J 0
(-635 1710);
DISPLAY 0.808511 (-635 1710);
WIRE 16 -1 (275 3650)(-475 3650);
FORCEPROP 2 LAST SIG_NAME A_BMC_ADCVREFN1
J 0
(-475 3660);
DISPLAY 0.808511 (-475 3660);
WIRE 16 -1 (275 3700)(-475 3700);
FORCEPROP 2 LAST SIG_NAME A_BMC_ADCVREFP1
J 0
(-475 3710);
DISPLAY 0.808511 (-475 3710);
WIRE 16 -1 (275 2700)(-650 2700);
FORCEPROP 2 LAST SIG_NAME P3V3_STBY_PLLAHVDD
J 0
(-610 2710);
DISPLAY 0.808511 (-610 2710);
WIRE 16 -1 (275 3950)(-475 3950);
FORCEPROP 2 LAST SIG_NAME A_BMC_ADCVREFP0
J 0
(-475 3960);
DISPLAY 0.808511 (-475 3960);
WIRE 16 -1 (275 3900)(-475 3900);
FORCEPROP 2 LAST SIG_NAME A_BMC_ADCVREFN0
J 0
(-475 3910);
DISPLAY 0.808511 (-475 3910);
WIRE 16 -1 (-1400 4600)(-1200 4600);
WIRE 16 -1 (-2450 2250)(-2150 2250);
WIRE 16 -1 (-3175 2875)(-2850 2875);
WIRE 16 -1 (-2000 975)(-2150 975);
WIRE 16 -1 (2625 1100)(2625 1450);
WIRE 16 -1 (2425 1100)(2625 1100);
WIRE 16 -1 (1975 1100)(2425 1100);
WIRE 16 -1 (2425 1100)(2425 1050);
WIRE 16 -1 (1975 1050)(2425 1050);
DOT 1 (2425 3750);
DOT 1 (3525 4000);
DOT 1 (3325 4000);
DOT 1 (3325 3650);
DOT 1 (3225 2675);
DOT 1 (3425 550);
DOT 1 (-1125 975);
DOT 1 (-1175 1250);
DOT 1 (-1375 1250);
DOT 1 (-1375 1600);
DOT 1 (-1700 2525);
DOT 1 (-1600 2525);
DOT 1 (-2500 2875);
DOT 1 (2425 3950);
DOT 1 (4075 3650);
DOT 1 (-1750 3600);
DOT 1 (4050 2325);
DOT 1 (3975 550);
DOT 1 (25 850);
DOT 1 (3600 550);
DOT 1 (4175 900);
DOT 1 (3975 900);
DOT 1 (2425 1100);
DOT 1 (2425 650);
DOT 1 (2425 600);
DOT 1 (2425 3150);
DOT 1 (3225 3375);
DOT 1 (2425 3300);
DOT 1 (2825 3375);
DOT 1 (-2175 1600);
DOT 1 (-2300 2525);
DOT 1 (-2075 2525);
DOT 1 (-2300 2875);
DOT 1 (-2075 2875);
DOT 1 (-1725 975);
DOT 1 (-1525 625);
DOT 1 (-1325 625);
DOT 1 (-1225 625);
DOT 1 (-1525 975);
DOT 1 (-1325 975);
DOT 1 (-1775 1250);
DOT 1 (-1975 1250);
DOT 1 (-1975 1600);
DOT 1 (-1775 1600);
DOT 1 (-1575 1600);
DOT 1 (-1825 2250);
DOT 1 (-1625 1850);
DOT 1 (-1175 1600);
DOT 1 (-1400 2250);
DOT 1 (-975 1250);
DOT 1 (-975 1600);
DOT 1 (-775 1600);
DOT 1 (25 550);
DOT 1 (25 700);
DOT 1 (25 750);
DOT 1 (25 1300);
DOT 1 (25 1350);
DOT 1 (25 1400);
DOT 1 (25 1450);
DOT 1 (25 1550);
DOT 1 (25 1600);
DOT 1 (-1875 2525);
DOT 1 (-1875 2875);
DOT 1 (-1700 2875);
DOT 1 (-1500 2875);
DOT 1 (-675 4175);
DOT 1 (-900 4600);
DOT 1 (-425 4600);
DOT 1 (25 2850);
DOT 1 (25 2950);
DOT 1 (25 3000);
DOT 1 (25 3100);
DOT 1 (50 4100);
DOT 1 (2625 100);
DOT 1 (2425 500);
DOT 1 (2425 850);
DOT 1 (2425 900);
DOT 1 (3050 550);
DOT 1 (2850 900);
DOT 1 (2425 1250);
DOT 1 (2425 1450);
DOT 1 (2425 1300);
DOT 1 (2425 1500);
DOT 1 (2425 1400);
DOT 1 (2425 1350);
DOT 1 (2425 1550);
DOT 1 (2425 1650);
DOT 1 (2425 1700);
DOT 1 (2425 2000);
DOT 1 (2425 1900);
DOT 1 (2425 2100);
DOT 1 (2425 2200);
DOT 1 (2425 2150);
DOT 1 (2425 2250);
DOT 1 (2425 2050);
DOT 1 (2775 1450);
DOT 1 (3025 1700);
DOT 1 (2825 2050);
DOT 1 (3250 550);
DOT 1 (3250 900);
DOT 1 (3425 900);
DOT 1 (3775 550);
DOT 1 (3600 900);
DOT 1 (3775 900);
DOT 1 (3225 1700);
DOT 1 (3575 2050);
DOT 1 (3750 2050);
DOT 1 (2425 2300);
DOT 1 (2425 2600);
DOT 1 (2425 2750);
DOT 1 (2425 2700);
DOT 1 (2425 2650);
DOT 1 (2425 2550);
DOT 1 (2425 2800);
DOT 1 (2425 2850);
DOT 1 (2425 2900);
DOT 1 (2425 2950);
DOT 1 (2425 3200);
DOT 1 (2425 3100);
DOT 1 (2425 3250);
DOT 1 (2825 2675);
DOT 1 (3025 2675);
DOT 1 (3025 3025);
DOT 1 (2425 3400);
DOT 1 (2425 3450);
DOT 1 (2425 3500);
DOT 1 (2425 3550);
DOT 1 (2425 3350);
DOT 1 (2425 3650);
DOT 1 (2425 3600);
DOT 1 (2425 3700);
DOT 1 (2425 4000);
DOT 1 (2425 3900);
DOT 1 (2425 3850);
DOT 1 (2775 3650);
DOT 1 (3025 3375);
DOT 1 (2950 3650);
DOT 1 (2600 4000);
DOT 1 (2775 4000);
DOT 1 (3225 2325);
DOT 1 (3400 2325);
DOT 1 (3225 3025);
DOT 1 (3400 3025);
DOT 1 (3575 2325);
DOT 1 (3575 2675);
DOT 1 (3575 3025);
DOT 1 (3750 2325);
DOT 1 (3750 2675);
DOT 1 (3950 2325);
DOT 1 (3950 2675);
DOT 1 (3750 3025);
DOT 1 (3950 3025);
DOT 1 (3150 3650);
DOT 1 (3525 3650);
DOT 1 (3150 4000);
DOT 1 (3575 3375);
DOT 1 (3725 3650);
DOT 1 (3725 4000);
DOT 1 (4150 2675);
DOT 1 (4250 3650);
DOT 1 (4425 3650);
DOT 1 (4250 4000);
DOT 1 (4725 3650);
DOT 1 (4825 4000);
DOT 1 (2950 4000);
DOT 1 (-875 1250);
DOT 1 (25 1500);
DOT 1 (-1575 1250);
DOT 1 (2425 1600);
DOT 1 (4075 550);
DOT 1 (3050 900);
DOT 1 (25 250);
DOT 1 (25 400);
DOT 1 (4625 4000);
DOT 1 (4425 4000);
DOT 1 (25 3400);
DOT 1 (-1750 3250);
DOT 1 (2425 700);
DOT 1 (2425 550);
DOT 1 (2425 750);
DOT 1 (2425 800);
DOT 1 (2425 3800);
DOT 1 (3950 1700);
DOT 1 (4625 3650);
DOT 1 (3400 2675);
DOT 1 (3400 3375);
DOT 1 (3750 1700);
DOT 1 (4050 1700);
DOT 1 (3025 2050);
DOT 1 (3025 2325);
DOT 1 (3575 1700);
DOT 1 (4050 3025);
DOT 1 (3750 3375);
DOT 1 (4150 3375);
DOT 1 (4075 4000);
DOT 1 (3900 4000);
DOT 1 (3950 3375);
DOT 1 (4150 2050);
DOT 1 (3950 2050);
DOT 1 (3225 2050);
DOT 1 (3900 3650);
QUIT
